G04 ================== begin FILE IDENTIFICATION RECORD ==================*
G04 Layout Name:  13130-1b.brd*
G04 Film Name:    L10*
G04 File Format:  Gerber RS274X*
G04 File Origin:  Cadence Allegro 16.5-S037*
G04 Origin Date:  Thu Nov 13 17:27:17 2014*
G04 *
G04 Layer:  VIA CLASS/L10*
G04 Layer:  PIN/L10*
G04 Layer:  ETCH/L10*
G04 Layer:  DRAWING FORMAT/LAYER_PCB_STORY*
G04 Layer:  DRAWING FORMAT/LAYER_L10*
G04 *
G04 Offset:    (0.00 0.00)*
G04 Mirror:    No*
G04 Mode:      Positive*
G04 Rotation:  0*
G04 FullContactRelief:  No*
G04 UndefLineWidth:     6.00*
G04 ================== end FILE IDENTIFICATION RECORD ====================*
%FSLAX35Y35*MOIN*%
%IR0*IPPOS*OFA0.00000B0.00000*MIA0B0*SFA1.00000B1.00000*%
%ADD11C,.02*%
%ADD15C,.022*%
%ADD14C,.06*%
%ADD12C,.017*%
%ADD10C,.028*%
%ADD13C,.056*%
%ADD16C,.01*%
%ADD17C,.012*%
%ADD18C,.04*%
%ADD19C,.015*%
%ADD20C,.004*%
%ADD21C,.005*%
%ADD22C,.006*%
%ADD23C,.0035*%
%ADD24C,.0045*%
%ADD25C,.0075*%
%ADD30C,.03004*%
%ADD38C,.04104*%
%ADD37C,.03204*%
%ADD28C,.05204*%
%ADD31C,.08004*%
%ADD29C,.04404*%
%ADD32C,.02704*%
%ADD36C,.04604*%
%ADD34C,.03804*%
%ADD33C,.06804*%
%ADD35C,.08704*%
%ADD26C,.11004*%
%ADD27C,.15004*%
G75*
%LPD*%
G75*
G36*
G01X309000Y268902D02*
G03X308910Y268900I4J-2202D01*
G01X303799D01*
X303498Y269202D01*
X284798D01*
X279500Y274500D01*
X232000D01*
X220500Y263000D01*
X176500D01*
X164500Y275000D01*
X137222D01*
X137196Y275007D01*
G03X135804I-696J-2507D01*
G01X135778Y275000D01*
X80794D01*
G02X80395Y275431I0J400D01*
G03X76005I-2195J169D01*
G02X75606Y275000I-399J-31D01*
G01X69202D01*
G02X69002Y275200I0J200D01*
G03X64598I-2202J0D01*
G02X64398Y275000I-200J0D01*
G01X48950D01*
X48906Y275142D01*
G03X44694I-2106J-642D01*
G01X44650Y275000D01*
X41500D01*
X34500Y268000D01*
Y219500D01*
X27000Y212000D01*
Y184400D01*
G02X26585Y184000I-400J0D01*
G03X24942Y183356I-85J-2200D01*
G02X24658I-142J141D01*
G03Y180244I-1558J-1556D01*
G02X24942I142J-141D01*
G03X26585Y179600I1558J1556D01*
G02X27000Y179200I15J-400D01*
G01Y122776D01*
G02X26477Y122395I-400J0D01*
G03Y118205I-677J-2095D01*
G02X27000Y117824I123J-381D01*
G01Y107000D01*
X34500Y99500D01*
X39723D01*
G03X43277I1777J1300D01*
G01X46500D01*
X50582Y95418D01*
X50595Y95395D01*
G03X51418Y94582I1905J1105D01*
G01X58599Y87401D01*
X58605Y87327D01*
G03X61684Y85483I2195J173D01*
G01X61722Y85500D01*
X63000D01*
X76000Y72500D01*
Y42500D01*
X74500Y41000D01*
X62000D01*
X61000Y42000D01*
Y58500D01*
X58500Y61000D01*
X5500D01*
X3001Y63499D01*
Y210001D01*
X3250Y210250D01*
Y218250D01*
X5782Y220782D01*
X5809Y220796D01*
G03X6904Y221891I-1209J2304D01*
G01X6918Y221918D01*
X13791Y228791D01*
G02X14388Y228756I283J-283D01*
G03X17480Y231848I1730J1362D01*
G02X17445Y232445I248J314D01*
G01X19500Y234500D01*
Y277500D01*
X25405Y283405D01*
X25475Y283413D01*
G03X27787Y285725I-275J2587D01*
G01X27795Y285795D01*
X29500Y287500D01*
X173000D01*
X183899Y276601D01*
X183898Y276518D01*
G03X188164Y274500I2602J-18D01*
G01X189564D01*
G03X192636I1536J2100D01*
G01X207278D01*
X207304Y274493D01*
G03X208696I696J2507D01*
G01X208722Y274500D01*
X211778D01*
X211804Y274493D01*
G03X213196I696J2507D01*
G01X213222Y274500D01*
X214000D01*
X218182Y278682D01*
G03X219304Y279791I-1182J2318D01*
G01X219318Y279818D01*
X227000Y287500D01*
X283500D01*
X291233Y279767D01*
G03X306151Y280151I7389J2910D01*
G01X313500Y287500D01*
X801500D01*
X810802Y278198D01*
X810817Y278156D01*
G03X814156Y274817I5183J1844D01*
G01X814198Y274802D01*
X814750Y274250D01*
Y263250D01*
X813000Y261500D01*
X806250D01*
X795750Y272000D01*
X774500D01*
X772500Y274000D01*
X759500D01*
X755500Y278000D01*
X344807D01*
X344785Y278175D01*
G03X340415I-2185J-275D01*
G01X340393Y278000D01*
X338000D01*
X329202Y269202D01*
X326100D01*
G03X324988Y268900I1J-2202D01*
G01X314000D01*
G02X313600Y269285I0J400D01*
G03X309200Y269110I-2200J-85D01*
G02X309000Y268902I-200J-8D01*
G37*
G36*
G01X29500Y194000D02*
X28202Y195298D01*
Y211202D01*
X34000Y217000D01*
X38500D01*
X39500Y218000D01*
Y235701D01*
X39522Y236460D01*
X39512D01*
Y236502D01*
X39500D01*
Y236508D01*
X39512D01*
Y236510D01*
G03X39500Y236694I-1512J-6D01*
G01Y249701D01*
X39522Y250460D01*
X39512D01*
Y250502D01*
X39500D01*
Y250508D01*
X39512D01*
Y250510D01*
G03X39500Y250694I-1512J-6D01*
G01Y260000D01*
X40298Y260798D01*
X41701D01*
X42000Y260500D01*
Y258699D01*
X41798Y258498D01*
Y232002D01*
X42000Y231801D01*
Y214175D01*
G02X41348Y213865I-400J1D01*
G03X41636Y211846I-948J-1165D01*
G01X41695Y211932D01*
X42000D01*
Y211500D01*
X42660Y210840D01*
Y210839D01*
X56496Y197002D01*
Y193002D01*
X88000Y161499D01*
Y136936D01*
G02X87277Y136700I-400J0D01*
G03Y134100I-1777J-1300D01*
G02X88000Y133864I323J-236D01*
G01Y131000D01*
X100500Y118500D01*
Y104500D01*
X107000Y98000D01*
Y91002D01*
X99998Y84000D01*
X93710D01*
X93694Y84183D01*
G03X92153Y86103I-2194J-183D01*
G02X91891Y86610I118J382D01*
G03X91428Y88782I-2091J690D01*
G02X91459Y89351I296J269D01*
G03X88372Y89518I-1459J1649D01*
G02X88341Y88949I-296J-269D01*
G03X89147Y85197I1459J-1649D01*
G02X89409Y84690I-118J-382D01*
G03X89306Y84183I2091J-689D01*
G01X89290Y84000D01*
X68000D01*
X61500Y90500D01*
X57199D01*
X46998Y100702D01*
X46798D01*
X44500Y103000D01*
Y104278D01*
X44507Y104304D01*
G03X41304Y107507I-2507J696D01*
G01X41278Y107500D01*
X38222D01*
X38196Y107507D01*
G03X36804I-696J-2507D01*
G01X36778Y107500D01*
X33722D01*
X33696Y107507D01*
G03X32304I-696J-2507D01*
G01X32278Y107500D01*
X31000D01*
X28500Y110000D01*
Y131500D01*
X31082Y134082D01*
G03X31905Y134895I-1082J1918D01*
G01X31918Y134918D01*
X32500Y135500D01*
Y143783D01*
G03Y146217I-2300J1217D01*
G01Y147983D01*
G03Y150417I-2300J1217D01*
G01Y152183D01*
G03Y154617I-2300J1217D01*
G01Y156211D01*
G03X32744Y158493I-2200J1389D01*
G02X33237Y159012I376J137D01*
G03X33047Y163921I763J2488D01*
G02X32500Y164293I-147J372D01*
G01Y170500D01*
X34000Y172000D01*
Y175950D01*
X34142Y175994D01*
G03X34879Y179817I-642J2106D01*
G01X34804Y179973D01*
X34850Y180100D01*
G03X34000Y183531I-1700J1400D01*
G01Y193500D01*
X33744Y193756D01*
X33926Y193939D01*
X33983Y193952D01*
G03X35160Y194654I-483J2148D01*
G02X35837Y194531I302J-263D01*
G03X37953Y193099I2063J769D01*
G02X38355Y192619I10J-400D01*
G03X40597Y195646I4362J-887D01*
G02X40021Y195891I-190J352D01*
G03X38905Y197259I-2121J-591D01*
G02X38775Y197864I183J356D01*
G03X36601Y197678I-1175J936D01*
G02X36576Y197060I-266J-299D01*
G03X36240Y196746I1327J-1757D01*
G02X35563Y196869I-302J263D01*
G03X33754Y198287I-2063J-769D01*
G02X33421Y198814I46J398D01*
G03X33502Y199336I-1421J488D01*
G01Y203164D01*
G03X30498I-1502J36D01*
G01Y199336D01*
G03X31464Y197897I1502J-36D01*
G02X31657Y197304I-142J-374D01*
G03X31833Y194661I1843J-1205D01*
G02X31530Y194000I-303J-261D01*
G01X29500D01*
G37*
G36*
G01X111000Y145000D02*
X108000Y148000D01*
Y157587D01*
G03X106175Y160901I-1900J1113D01*
G01X106097Y160903D01*
X93750Y173250D01*
Y177750D01*
X91000Y180500D01*
X75500D01*
X65500Y190500D01*
Y193683D01*
G03X63582Y197474I-2300J1217D01*
G01X63516Y197484D01*
X47062Y213938D01*
Y227261D01*
G03X46776Y228347I-2201J1D01*
G01X46750Y228393D01*
Y228750D01*
X43000Y232500D01*
Y258000D01*
X43500Y258500D01*
Y261500D01*
X42500Y262500D01*
X42000D01*
X41500Y262000D01*
X41421D01*
G03X39579I-921J-2000D01*
G01X37000D01*
X36000Y263000D01*
Y266500D01*
X37000Y267500D01*
X41062D01*
G03X44372I1655J2972D01*
G01X47500D01*
X52000Y263000D01*
Y258000D01*
X49500Y255500D01*
Y236000D01*
X54888Y230612D01*
X54863Y230504D01*
G03X54984Y229144I2146J-494D01*
G01X55000Y229107D01*
Y225500D01*
X56000Y224500D01*
X56937D01*
X56965Y224492D01*
G03X58235I635J2108D01*
G01X58263Y224500D01*
X61000D01*
X72379Y213121D01*
G02X72102Y212439I-283J-282D01*
G03X74339Y210202I35J-2202D01*
G02X75021Y210479I400J-6D01*
G01X83922Y201578D01*
X83869Y201454D01*
G03X83925Y199620I2029J-856D01*
G02X83741Y199082I-358J-178D01*
G03X86579Y198248I959J-1982D01*
G02X86679Y198539I171J104D01*
G03X86754Y198569I-780J2059D01*
G01X86878Y198622D01*
X90500Y195000D01*
X95610D01*
G03X95790I90J2200D01*
G01X108500D01*
X114500Y201000D01*
X137500D01*
X141500Y197000D01*
Y195000D01*
X140500Y194000D01*
X138000D01*
X136000Y196000D01*
X116500D01*
X112500Y192000D01*
Y181500D01*
X125000Y169000D01*
Y158790D01*
G03Y158610I2200J-90D01*
G01Y157500D01*
X126500Y156000D01*
X133000D01*
X133583Y156583D01*
G03X134213Y157000I-882J2017D01*
G01X136187D01*
G03X138413I1113J1900D01*
G01X139687D01*
G03X141913I1113J1900D01*
G01X143387D01*
G03X146244Y160244I1113J1900D01*
G01X148500Y162500D01*
X153500D01*
X159000Y168000D01*
Y168272D01*
X159017Y168310D01*
G03X159000Y170115I-2017J884D01*
G01Y177500D01*
X165000Y183500D01*
X167000D01*
X167500Y183000D01*
Y177000D01*
X165500Y175000D01*
Y173000D01*
X167000Y171500D01*
X176588D01*
X176622Y171487D01*
G03X177194Y171389I537J1413D01*
G01X180965Y171474D01*
G03X181198Y171497I-32J1511D01*
G01X181215Y171500D01*
X184000D01*
X185500Y170000D01*
X192500D01*
X194000Y168500D01*
Y162160D01*
X190840Y159000D01*
X170500D01*
X166000Y154500D01*
X163000D01*
X162903Y154403D01*
X162825Y154401D01*
G03X160699Y152275I75J-2201D01*
G01X160697Y152197D01*
X159500Y151000D01*
X158475D01*
X158434Y151019D01*
G03X155302Y148897I-934J-1994D01*
G01X155307Y148807D01*
X154500Y148000D01*
X147083D01*
X147037Y148137D01*
G03X140963I-3037J-1012D01*
G01X140917Y148000D01*
X140001D01*
X139947Y148042D01*
G03X136416Y146581I-1347J-1742D01*
G01X136407Y146514D01*
X136095Y146202D01*
X129295D01*
X128094Y145000D01*
X121000D01*
G03X118200I-1400J-1700D01*
G01X112640D01*
G03X112460I-90J-2200D01*
G01X111000D01*
G37*
G36*
G01X75000Y218000D02*
X64500Y228500D01*
Y263000D01*
X68000Y266500D01*
X73000D01*
X79500Y273000D01*
X142422D01*
G02X142696Y272308I0J-400D01*
G03X145704I1504J-1608D01*
G02X145978Y273000I274J292D01*
G01X163000D01*
X174500Y261500D01*
X205000D01*
X209000Y257500D01*
Y224000D01*
X203702Y218702D01*
X114238D01*
G02X114002Y219424I1J400D01*
G03X114041Y222946I-1302J1776D01*
G02X114057Y223592I244J317D01*
G03X111459Y223654I-1257J1808D01*
G02X111443Y223008I-244J-317D01*
G03X111398Y219424I1257J-1808D01*
G02X111162Y218702I-237J-322D01*
G01X102266D01*
G02X102010Y219409I0J400D01*
G03X99713Y219085I-1410J1691D01*
G01X99832Y219032D01*
Y218702D01*
X99434D01*
X98732Y218000D01*
X96468D01*
G03X93932I-1268J-1800D01*
G01X75000D01*
G37*
G36*
G01X134500Y163500D02*
X133702Y164298D01*
Y185595D01*
X135305Y187198D01*
X135701D01*
X135755Y187157D01*
G03X135702Y190602I1345J1744D01*
G01X133895D01*
X130298Y187005D01*
Y169798D01*
X129500Y169000D01*
X127000D01*
X114000Y182000D01*
Y191000D01*
X117500Y194500D01*
X135801D01*
X137502Y192798D01*
X140998D01*
X141199Y193000D01*
X141500D01*
X143000Y194500D01*
Y197500D01*
X136500Y204000D01*
X130500D01*
X129500Y205000D01*
Y207500D01*
X133000Y211000D01*
X138500D01*
X140000Y209500D01*
Y207500D01*
X142000Y205500D01*
X146052D01*
X146067Y205498D01*
G03X146725I329J2177D01*
G01X146740Y205500D01*
X147500D01*
X149500Y207500D01*
X159000D01*
X162000Y210500D01*
X181000D01*
X182000Y209500D01*
Y208000D01*
X170500Y196500D01*
Y190000D01*
X181550Y178950D01*
Y175950D01*
X180100Y174500D01*
X176000D01*
X175000Y173500D01*
X173500D01*
X169000Y178000D01*
Y183500D01*
X167500Y185000D01*
X164500D01*
X158000Y178500D01*
Y178199D01*
X157798Y177998D01*
Y168798D01*
X152702Y163702D01*
X148002D01*
X147801Y163500D01*
X134500D01*
G37*
G36*
G01X370500Y155000D02*
X362000Y163500D01*
Y167238D01*
X362110Y167293D01*
G03Y169707I-610J1207D01*
G01X362000Y169762D01*
Y173738D01*
X362110Y173793D01*
G03Y176207I-610J1207D01*
G01X362000Y176262D01*
Y177410D01*
G03Y179590I-800J1090D01*
G01Y180257D01*
G03Y182561I-708J1152D01*
G01Y183343D01*
G03Y185657I-700J1157D01*
G01Y186388D01*
G03Y188812I-600J1212D01*
G01Y189570D01*
G03Y191830I-743J1130D01*
G01Y192394D01*
G03Y194654I-743J1130D01*
G01Y222000D01*
X365000Y225000D01*
X375000D01*
X378500Y228500D01*
X381488D01*
X381543Y228390D01*
G03X382033Y227854I1206J611D01*
G02X382021Y227169I-213J-339D01*
G03X383417Y227146I679J-1169D01*
G02X383429Y227831I213J339D01*
G03X383957Y228390I-678J1170D01*
G01X384012Y228500D01*
X387594D01*
G02X387961Y227940I0J-400D01*
G03X389939Y228532I1239J-540D01*
G02X389928Y229194I219J335D01*
G03X390498Y230400I-778J1106D01*
G01X390492Y230492D01*
X397499Y237499D01*
X397573Y237505D01*
G03X399595Y239527I-173J2195D01*
G01X399601Y239601D01*
X403500Y243500D01*
Y244621D01*
G02X404177Y244910I400J0D01*
G03X403663Y247336I1523J1590D01*
G02X402989Y247229I-370J152D01*
G03X402359Y247667I-1150J-982D01*
G01X402317Y247683D01*
X401000Y249000D01*
X363000D01*
X358000Y254000D01*
X328208D01*
X328200Y254192D01*
G03X324529Y255739I-2200J-92D01*
G01X324388Y255612D01*
X324250Y255750D01*
X324066D01*
X324008Y255804D01*
G03X320992I-1508J-1604D01*
G01X320934Y255750D01*
X320566D01*
X320508Y255804D01*
G03X317492I-1508J-1604D01*
G01X317434Y255750D01*
X316960D01*
X316904Y255796D01*
G03X314042Y255750I-1404J-1696D01*
G01X309876D01*
X309856Y255754D01*
G03X308944I-456J-2154D01*
G01X308924Y255750D01*
X306750D01*
X306693Y255693D01*
X306581Y255724D01*
G03X303815Y253326I-581J-2124D01*
G02X303418Y252876I-397J-50D01*
G01X301502D01*
G02X301102Y253280I0J400D01*
G03X297433Y254942I-2202J20D01*
G02X297150Y254959I-133J149D01*
G03X293687Y254750I-1650J-1459D01*
G01X289508D01*
X289460Y254879D01*
G03X286287Y256000I-2060J-779D01*
G01X280023D01*
G03X277377I-1323J-1760D01*
G01X276414D01*
X276369Y256025D01*
G03X274187Y256000I-1069J-1925D01*
G01X264500D01*
X263393Y254893D01*
X263325Y254885D01*
G03X261415Y252975I275J-2185D01*
G01X261407Y252907D01*
X256000Y247500D01*
X219500D01*
X215000Y252000D01*
Y259500D01*
X217000Y261500D01*
X221500D01*
X232500Y272500D01*
X264524D01*
G02X264905Y271977I0J-400D01*
G03X269095I2095J-677D01*
G02X269476Y272500I381J123D01*
G01X279500D01*
X284000Y268000D01*
X285437D01*
G03X289063I1813J1250D01*
G01X303000D01*
X307000Y264000D01*
X316413D01*
X316446Y263842D01*
G03X320158Y262744I2154J458D01*
G02X320442I142J-141D01*
G03X324154Y263842I1558J1556D01*
G01X324187Y264000D01*
X329387D01*
X332288Y261098D01*
X343738D01*
X344139Y261500D01*
X362500D01*
X366500Y257500D01*
X390887D01*
X390888Y257498D01*
X409492D01*
X410692Y256298D01*
X410693D01*
X415000Y251992D01*
Y243000D01*
X399000Y227000D01*
Y226157D01*
G03X399759Y223649I700J-1157D01*
G01X399847Y223653D01*
X401500Y222000D01*
Y221774D01*
G02X400803Y221506I-400J0D01*
G03Y219694I-1003J-906D01*
G02X401500Y219426I297J-268D01*
G01Y212000D01*
X400500Y211000D01*
X399500D01*
X388500Y200000D01*
Y194510D01*
G03Y192690I1000J-910D01*
G01Y191369D01*
G03X388576Y189440I984J-927D01*
G02X388534Y188814I-268J-296D01*
G03X390546Y187175I766J-1114D01*
G02X391197Y187303I369J-155D01*
G01X391282Y187218D01*
X391296Y187168D01*
G03X391500Y186749I1300J374D01*
G01Y185288D01*
G03Y183786I1124J-751D01*
G01Y182473D01*
G03Y180899I1099J-787D01*
G01Y176055D01*
G02X390855Y175740I-400J1D01*
G03Y173604I-830J-1068D01*
G02X391500Y173289I245J-316D01*
G01Y168500D01*
X391737Y168263D01*
X391749Y168202D01*
G03X392824Y167127I1328J253D01*
G01X392885Y167115D01*
X394000Y166000D01*
Y165000D01*
X393000Y164000D01*
X380000D01*
X376000Y160000D01*
Y158000D01*
X374978Y156978D01*
X374852Y157034D01*
G03X372984Y155491I-552J-1234D01*
G02X372594Y155000I-390J-91D01*
G01X370500D01*
G37*
G36*
G01X237450Y96250D02*
X239007Y94693D01*
X239015Y94625D01*
G03X240992Y92708I2185J275D01*
G01X241098Y92602D01*
Y76545D01*
X240553Y76000D01*
X239500D01*
X238868Y76632D01*
X238853Y76676D01*
G03X236716Y78813I-3223J-1086D01*
G01X236672Y78828D01*
X233000Y82500D01*
Y93129D01*
X233150Y93168D01*
G03X234797Y95450I-550J2132D01*
G01X234791Y95541D01*
X235500Y96250D01*
X237450D01*
G37*
G36*
G01X353500Y68500D02*
X338000Y84000D01*
Y92984D01*
X338013Y93018D01*
G03Y93982I-1263J482D01*
G01X338000Y94016D01*
Y95188D01*
X338013Y95222D01*
G03Y96186I-1263J482D01*
G01X338000Y96220D01*
Y96500D01*
X336500Y98000D01*
Y99253D01*
X336502Y99255D01*
Y120639D01*
X338363Y122500D01*
X342500D01*
X342682Y122682D01*
X342783Y122666D01*
G03X344334Y124217I217J1334D01*
G01X344318Y124318D01*
X344500Y124500D01*
Y126000D01*
X349000Y130500D01*
Y135000D01*
X350955Y136955D01*
X351019Y136966D01*
G03X352134Y138081I-219J1334D01*
G01X352145Y138145D01*
X357000Y143000D01*
Y151000D01*
X359500Y153500D01*
X362991D01*
G02X363381Y153012I0J-400D01*
G03X366019I1319J-299D01*
G02X366409Y153500I390J88D01*
G01X377000D01*
X379000Y155500D01*
X385000D01*
X386000Y154500D01*
X386931D01*
G03X387069I69J1350D01*
G01X388000D01*
X389000Y153500D01*
Y147621D01*
G03X390713Y145529I847J-1054D01*
G01X390854Y145646D01*
X393000Y143500D01*
X402100D01*
G03X402907Y143041I1031J874D01*
G01X402970Y143030D01*
X404500Y141500D01*
Y136000D01*
X403500Y135000D01*
X400321D01*
G03X398221Y133405I-869J-1036D01*
G01X398278Y133278D01*
X397500Y132500D01*
X392500D01*
X392000Y133000D01*
Y138000D01*
X391000Y139000D01*
X387000D01*
X386445Y138445D01*
X386391Y138432D01*
G03X386000Y135966I317J-1314D01*
G01Y135498D01*
X385728Y135226D01*
Y130228D01*
X385288Y129788D01*
X385250Y129773D01*
G03X384487Y128035I500J-1256D01*
G01X384500Y128001D01*
Y126501D01*
G03Y124637I979J-932D01*
G01Y123416D01*
G03X384572Y121572I1023J-883D01*
G01X383433Y120433D01*
G02X382796Y120530I-283J283D01*
G03X380317Y119473I-1196J-630D01*
G01X380356Y119356D01*
X380000Y119000D01*
Y108500D01*
X379212Y107712D01*
X379162Y107698D01*
G03X378224Y106760I364J-1302D01*
G01X378210Y106710D01*
X375000Y103500D01*
Y91590D01*
G03Y89410I800J-1090D01*
G01Y88090D01*
G03Y85910I800J-1090D01*
G01Y84590D01*
G03Y82410I800J-1090D01*
G01Y80000D01*
X365617Y70617D01*
X365594Y70604D01*
G03X364796Y69806I1106J-1904D01*
G01X364783Y69783D01*
X363500Y68500D01*
X353500D01*
G37*
G36*
G01X440000Y242000D02*
X437539Y244461D01*
G03X436911Y245089I-1839J-1211D01*
G01X434874Y247126D01*
G03X434481Y247521I-1745J-1343D01*
G01X434472Y247528D01*
X434000Y248000D01*
X428500D01*
X421500Y255000D01*
Y255838D01*
G03X422603Y258452I-1000J1962D01*
G01X422567Y258567D01*
X432500Y268500D01*
X448298D01*
Y268088D01*
X452498Y263888D01*
X472101D01*
G03X473572Y264452I-1J2202D01*
G02X473855Y264436I134J-149D01*
G03X476981Y264270I1645J1464D01*
G02X477519I269J-296D01*
G03X480695Y264494I1481J1630D01*
G02X480978Y264519I154J-128D01*
G03X484602Y266199I1422J1681D01*
G02X485002Y266598I400J-1D01*
G01X504206D01*
G03X506872Y270057I1110J1902D01*
G01X506447Y270481D01*
G02X506677Y271160I283J283D01*
G03X505443Y271652I-181J1340D01*
G02X505131Y271002I-312J-250D01*
G01X473511D01*
X470801Y268292D01*
X454322D01*
X452702Y269912D01*
Y273001D01*
X452868Y273029D01*
G03X454566Y275962I-368J2171D01*
G02X454941Y276500I375J138D01*
G01X457959D01*
G02X458334Y275962I0J-400D01*
G03X461923Y273610I2066J-762D01*
G02X462477I277J-289D01*
G03X463920Y272999I1524J1590D01*
G02X464305Y272631I-14J-400D01*
G03X468695I2195J169D01*
G02X469080Y272999I399J-32D01*
G03X470513Y273600I-80J2201D01*
G02X470796Y273592I138J-145D01*
G03X474433Y275946I1604J1508D01*
G02X474802Y276500I369J154D01*
G01X495234D01*
G02X495605Y275953I-1J-400D01*
G03X498399I1397J-553D01*
G02X498770Y276500I372J147D01*
G01X582500D01*
X584000Y275000D01*
Y271739D01*
G02X583372Y271410I-400J0D01*
G03Y269190I-772J-1110D01*
G02X584000Y268861I228J-329D01*
G01Y245000D01*
X582000Y243000D01*
X569000D01*
X568576Y242576D01*
X477987D01*
X477410Y242000D01*
X440000D01*
G37*
G36*
G01X455999Y3001D02*
X453500Y5500D01*
Y21622D01*
G03X453502Y21700I-2200J95D01*
G01Y40990D01*
X453500Y40991D01*
Y41500D01*
X453400Y41600D01*
Y56400D01*
X455500Y58500D01*
X526500D01*
X539500Y45500D01*
X604500D01*
X612500Y37500D01*
Y34649D01*
G02X611836Y34349I-400J0D01*
G03Y32317I-892J-1016D01*
G02X612500Y32017I264J-300D01*
G01Y19156D01*
G02X612077Y18757I-400J0D01*
G03Y16057I-77J-1350D01*
G02X612500Y15658I23J-399D01*
G01Y13630D01*
G02X611838Y13328I-400J0D01*
G03Y11286I-886J-1021D01*
G02X612500Y10984I262J-302D01*
G01Y4500D01*
X611001Y3001D01*
X455999D01*
G37*
G36*
G01X753500Y3000D02*
X752000Y4500D01*
Y31000D01*
X719000Y64000D01*
Y67000D01*
X721250Y69250D01*
X752250D01*
X771500Y50000D01*
Y31500D01*
X772422Y30578D01*
X772437Y30538D01*
G03X773731Y29244I2063J769D01*
G01X773771Y29229D01*
X777000Y26000D01*
X789000D01*
X792500Y22500D01*
X807000D01*
X809500Y25000D01*
Y116000D01*
X806000Y119500D01*
X799500D01*
X798000Y121000D01*
Y128000D01*
X803500Y133500D01*
Y149500D01*
X769000Y184000D01*
Y205500D01*
X750500Y224000D01*
X744763D01*
X744735Y224008D01*
G03X743465I-635J-2108D01*
G01X743437Y224000D01*
X741000D01*
X737902Y220902D01*
X737893D01*
X736491Y219500D01*
X663000D01*
X656000Y226500D01*
X647000D01*
X640500Y233000D01*
Y265500D01*
X639500Y266500D01*
X639160D01*
X639104Y266547D01*
G03X638090Y266916I-1013J-1207D01*
G01X637366D01*
X636949Y266500D01*
X635339D01*
G03X634280Y266908I-1058J-1168D01*
G01X633616D01*
X633207Y266500D01*
X631584D01*
G03X629326I-1129J-1100D01*
G01X627861D01*
G03X625441I-1210J-1011D01*
G01X623775D01*
G03X622023I-876J-1311D01*
G01X620122D01*
G03X618078I-1022J-1200D01*
G01X618000D01*
X615000Y269500D01*
X610721D01*
G02X610327Y269970I0J400D01*
G03X610099Y270988I-1331J236D01*
G02X610305Y271600I327J231D01*
G03X608793Y272107I-409J1289D01*
G02X608587Y271495I-327J-231D01*
G03X608097Y269196I409J-1289D01*
G02X608114Y268614I-266J-299D01*
G01X606500Y267000D01*
X604500D01*
X603500Y268000D01*
X594500D01*
X593500Y269000D01*
Y274000D01*
X596000Y276500D01*
X754500D01*
X758500Y272500D01*
X765500D01*
X768000Y270000D01*
X794500D01*
X806500Y258000D01*
Y248489D01*
G03Y245711I2200J-1389D01*
G01Y244289D01*
G03Y241511I2200J-1389D01*
G01Y239689D01*
G03Y236911I2200J-1389D01*
G01Y235489D01*
G03Y232711I2200J-1389D01*
G01Y228698D01*
G03Y228502I2600J-98D01*
G01Y224498D01*
G03Y224302I2600J-98D01*
G01Y204000D01*
X810716Y199784D01*
G02X810442Y199101I-283J-283D01*
G03X808641Y194680I58J-2601D01*
G02Y194120I-286J-280D01*
G03X812359I1859J-1820D01*
G02Y194680I286J280D01*
G03X813101Y196442I-1859J1820D01*
G02X813784Y196716I400J-9D01*
G01X823500Y187000D01*
Y14500D01*
X812000Y3000D01*
X753500D01*
G37*
G36*
G01X639500Y35500D02*
X642201Y32799D01*
X642217Y32757D01*
G03X643000Y31877I1484J532D01*
G01Y31439D01*
X642946Y31381D01*
G03X643000Y29178I1154J-1074D01*
G01Y27523D01*
G02X642519Y27131I-400J0D01*
G03Y24483I-273J-1324D01*
G02X643000Y24091I81J-392D01*
G01Y23771D01*
X642674Y23444D01*
Y22259D01*
G02X642471Y22059I-200J0D01*
G03X641624Y19638I-20J-1352D01*
G01Y13247D01*
X642500Y12370D01*
Y11500D01*
X642000Y11000D01*
X623500D01*
X623000Y11500D01*
Y18260D01*
G02X623430Y18659I400J0D01*
G03Y21355I102J1348D01*
G02X623000Y21754I-30J399D01*
G01Y23362D01*
G02X623435Y23760I400J0D01*
G03X623868Y26422I120J1347D01*
G01X623813Y26435D01*
X623632Y26617D01*
X623804Y26789D01*
Y33064D01*
X623802Y33066D01*
Y33817D01*
X624202Y34217D01*
Y34702D01*
X625000Y35500D01*
X639500D01*
G37*
G36*
G01X755500Y100000D02*
X748500Y107000D01*
X740520D01*
X738500Y109020D01*
Y117910D01*
G03Y118090I-2200J90D01*
G01Y124500D01*
X732500Y130500D01*
Y151500D01*
X714000Y170000D01*
X686000D01*
X675000Y181000D01*
Y186000D01*
X695500Y206500D01*
X763000D01*
X767250Y202250D01*
Y182875D01*
X784000Y166125D01*
X784125D01*
X801750Y148500D01*
Y134250D01*
X796500Y129000D01*
Y118500D01*
X778000Y100000D01*
X755500D01*
G37*
%LPC*%
G75*
G36*
G01X763842Y279444D02*
G03X763558I-142J-141D01*
G02Y282556I-1558J1556D01*
G03X763842I142J141D01*
G02Y279444I1558J-1556D01*
G37*
G36*
G01X319011Y276633D02*
G03X318550Y276325I-70J-394D01*
G02X314320Y277524I-2150J476D01*
G03X313925Y278055I-377J132D01*
G02X313887Y278054I-77J2201D01*
G03X313499Y277677I11J-400D01*
G02X311237Y280001I-2199J123D01*
G03X311625Y280378I-11J400D01*
G02X314637Y282302I2199J-123D01*
G03X314897Y282414I74J186D01*
G02X318743Y282877I2048J-808D01*
G03X319459Y283014I327J230D01*
G02X323513Y283590I2141J-514D01*
G03X324051Y283436I348J198D01*
G02X325023Y279299I1049J-1936D01*
G03X324654Y278715I-14J-400D01*
G02X320786Y276612I-1954J-1015D01*
G03X320278Y276781I-348J-198D01*
G02X319011Y276633I-878J2019D01*
G37*
G36*
G01X11372Y148030D02*
G03X11385Y148643I-250J312D01*
G02X14728Y148570I1715J1957D01*
G03X14715Y147957I250J-312D01*
G02X14723Y144050I-1715J-1957D01*
G03Y143450I264J-300D01*
G02Y139550I-1723J-1950D01*
G03Y138950I264J-300D01*
G02X11277I-1723J-1950D01*
G03Y139550I-264J300D01*
G02Y143450I1723J1950D01*
G03Y144050I-264J300D01*
G02X11372Y148030I1723J1950D01*
G37*
G36*
G01X15440Y107333D02*
G03Y106667I222J-333D01*
G02X12560I-1440J-2167D01*
G03Y107333I-222J333D01*
G02X15440I1440J2167D01*
G37*
G36*
G01X25900Y79742D02*
G02X22714Y78542I-899J-2442D01*
G03X22500Y79108I-352J191D01*
G02X25794Y82570I900J2442D01*
G03X26506Y82523I368J157D01*
G02X26442Y80393I1894J-1123D01*
G03X25728Y80388I-356J-183D01*
G02X25686Y80308I-2324J1169D01*
G03X25900Y79742I352J-191D01*
G37*
G36*
G01X36302Y212164D02*
Y208336D01*
G02X33298I-1502J-36D01*
G01Y212164D01*
G02X36302I1502J36D01*
G37*
G36*
G01X53372Y191420D02*
Y187555D01*
X53362Y187471D01*
G02X50348Y187640I-1502J169D01*
G01Y191411D01*
G02X53372Y191420I1512J-1D01*
G37*
G36*
G01X59379Y182868D02*
X55719D01*
G02X55720Y185892I1J1512D01*
G01X59379D01*
G02X60890Y184390I0J-1511D01*
G01Y184295D01*
X60881Y184211D01*
G02X59379Y182868I-1502J168D01*
G37*
G36*
G01X54153Y132402D02*
G03X54685Y132387I274J291D01*
G02X54590Y129098I1415J-1687D01*
G03X54058Y129113I-274J-291D01*
G02X54153Y132402I-1415J1687D01*
G37*
G36*
G01X67273Y125938D02*
G03X67119Y125292I140J-375D01*
G02X64727Y125862I-1619J-1492D01*
G03X64881Y126508I-140J375D01*
G02X67273Y125938I1619J1492D01*
G37*
G36*
G01X69756Y93342D02*
G03Y93058I141J-142D01*
G02X66644I-1556J-1558D01*
G03Y93342I-141J142D01*
G02X69756I1556J1558D01*
G37*
G36*
G01X59140Y212626D02*
G03X59109Y212088I280J-286D01*
G02X55860Y212274I-1709J-1388D01*
G03X55891Y212812I-280J286D01*
G02X59140Y212626I1709J1388D01*
G37*
G36*
G01X85342Y189444D02*
G03X85058I-142J-141D01*
G02Y192556I-1558J1556D01*
G03X85342I142J141D01*
G02Y189444I1558J-1556D01*
G37*
G36*
G01X76842Y190176D02*
G03X77078Y189649I371J-150D01*
G02X73943Y188494I-878J-2449D01*
G03X73781Y189048I-347J199D01*
G02X72599Y191080I1019J1952D01*
G03X72027Y191455I-400J14D01*
G02X73483Y193483I-1127J2346D01*
G03X74021Y193060I397J-49D01*
G02X76842Y190176I779J-2060D01*
G37*
G36*
G01X169146Y162535D02*
G03X169148Y162252I142J-141D01*
G02X166037Y162233I-1546J-1568D01*
G03X166035Y162516I-142J141D01*
G02X169146Y162535I1546J1568D01*
G37*
G36*
G01X82342Y267944D02*
G03X82058I-142J-141D01*
G02Y271056I-1558J1556D01*
G03X82342I142J141D01*
G02Y267944I1558J-1556D01*
G37*
G36*
G01X101979Y265710D02*
G03X102072Y265111I304J-259D01*
G02X98721Y264590I-1372J-2211D01*
G03X98628Y265189I-304J259D01*
G02X101979Y265710I1372J2211D01*
G37*
G36*
G01X71410Y246899D02*
G03X71677Y246799I183J81D01*
G02X73008Y246964I924J-1999D01*
G03X73469Y247256I74J393D01*
G02X77067Y248342I2131J-556D01*
G03X77350Y248359I133J149D01*
G02X80695Y248306I1650J-1459D01*
G03X80978Y248281I154J128D01*
G02X80705Y245194I1422J-1681D01*
G03X80422Y245219I-154J-128D01*
G02X77533Y245258I-1422J1681D01*
G03X77250Y245241I-133J-149D01*
G02X75192Y244536I-1650J1459D01*
G03X74731Y244244I-74J-393D01*
G02X70590Y243901I-2131J556D01*
G03X70323Y244001I-183J-81D01*
G02X71410Y246899I-923J1999D01*
G37*
G36*
G01X259653Y267108D02*
G03X260114Y266798I391J84D01*
G02X258347Y264167I386J-2168D01*
G03X257886Y264477I-391J-84D01*
G02X255695Y265383I-386J2168D01*
G03X255052Y265400I-328J-229D01*
G02X255278Y268258I-2052J1600D01*
G03X255915Y268174I350J194D01*
G02X259653Y267108I1585J-1529D01*
G37*
G36*
G01X279973Y260315D02*
G03X279417Y260349I-296J-270D01*
G02X280715Y264266I-2606J3037D01*
G03X281181Y263961I390J88D01*
G02X283203Y263307I418J-2162D01*
G03X283486Y263299I145J137D01*
G02X283396Y260192I1514J-1599D01*
G03X283113Y260200I-145J-137D01*
G02X279973Y260315I-1514J1599D01*
G37*
G36*
G01X377162Y212658D02*
G03Y212042I255J-308D01*
G02X375438I-862J-1042D01*
G03Y212658I-255J308D01*
G02X375353Y214665I862J1042D01*
G03Y215235I-281J285D01*
G02X377247I947J965D01*
G03Y214665I281J-285D01*
G02X377162Y212658I-947J-965D01*
G37*
G36*
G01X385675Y207491D02*
G03X385637Y206912I256J-308D01*
G02X383779Y207033I-993J-918D01*
G03X383817Y207612I-256J308D01*
G02X385675Y207491I993J918D01*
G37*
G36*
G01X365617Y187672D02*
G03X365573Y187077I244J-317D01*
G02X363775Y187209I-973J-939D01*
G03X363819Y187804I-244J317D01*
G02X363884Y189745I973J939D01*
G03X363898Y190028I-134J148D01*
G02X363964Y191922I997J913D01*
G03X363971Y192205I-137J145D01*
G02X365878Y192160I976J936D01*
G03X365871Y191877I137J-145D01*
G02X365803Y189939I-976J-936D01*
G03X365789Y189656I134J-148D01*
G02X365617Y187672I-997J-913D01*
G37*
G36*
G01X373536Y180424D02*
G03X373490Y179899I277J-289D01*
G02X371464Y180076I-1091J-799D01*
G03X371510Y180601I-277J289D01*
G02X373536Y180424I1091J799D01*
G37*
G36*
G01X365623Y176211D02*
G03X365622Y175686I301J-263D01*
G02X363584Y175692I-1022J-886D01*
G03X363585Y176217I-301J263D01*
G02X365623Y176211I1022J886D01*
G37*
G36*
G01X235679Y257536D02*
G02X231108Y257933I-2179J1422D01*
G03X230376Y257939I-367J-158D01*
G02X230392Y260025I-2376J1061D01*
G03X231124Y260019I367J158D01*
G02X235655Y260416I2376J-1061D01*
G03X236321Y260422I331J225D01*
G02X240450Y260723I2179J-1422D01*
G03X241050I300J264D01*
G02X245167Y260440I1950J-1723D01*
G03X245833I333J222D01*
G02X249950Y260723I2167J-1440D01*
G03X250550I300J264D01*
G02Y257277I1950J-1723D01*
G03X249950I-300J-264D01*
G02X245833Y257560I-1950J1723D01*
G03X245167I-333J-222D01*
G02X241050Y257277I-2167J1440D01*
G03X240450I-300J-264D01*
G02X236345Y257542I-1950J1723D01*
G03X235679Y257536I-331J-225D01*
G37*
G36*
G01X380429Y214669D02*
G02X379033Y214646I-679J-1169D01*
G03X379021Y215331I-213J339D01*
G02X378838Y217542I679J1169D01*
G03Y218158I-255J308D01*
G02X380562I862J1042D01*
G03Y217542I255J-308D01*
G02X380417Y215354I-862J-1042D01*
G03X380429Y214669I213J-339D01*
G37*
G36*
G01X370321Y196942D02*
G02X370082Y195419I978J-934D01*
G03X369433Y195521I-360J-174D01*
G02X369672Y197044I-978J934D01*
G03X370321Y196942I360J174D01*
G37*
G36*
G01X382777Y195306D02*
G02X382404Y196578I-1317J304D01*
G03X383073Y196774I279J286D01*
G02X383446Y195502I1317J-304D01*
G03X382777Y195306I-279J-286D01*
G37*
G36*
G01X374805Y191436D02*
G02X373134Y191389I-806J-1086D01*
G03X373117Y192017I-256J307D01*
G02X374929Y194005I805J1086D01*
G03X375586Y194096I298J267D01*
G02X376210Y194716I1213J-597D01*
G03X376233Y195424I-175J360D01*
G02X377490Y195384I667J1176D01*
G03X377467Y194676I175J-360D01*
G02X375793Y192598I-667J-1176D01*
G03X375136Y192507I-298J-267D01*
G02X374788Y192064I-1214J596D01*
G03X374805Y191436I256J-307D01*
G37*
G36*
G01X369831Y187264D02*
G02X368334Y187363I-823J-1073D01*
G03X368378Y188027I-199J347D01*
G02X368354Y190154I822J1073D01*
G03X368332Y190794I-251J312D01*
G02X369952Y190849I773J1109D01*
G03X369974Y190209I251J-312D01*
G02X369875Y187928I-774J-1109D01*
G03X369831Y187264I199J-347D01*
G37*
G36*
G01X381588Y178224D02*
G02X380403Y178715I-1048J-854D01*
G03X380672Y179366I-41J398D01*
G02X381107Y181425I1048J854D01*
G03X381125Y182128I-181J356D01*
G02X380502Y183680I675J1172D01*
G03X380208Y184182I-384J112D01*
G02X379851Y186680I302J1318D01*
G03X379994Y187242I-196J349D01*
G02X381799Y186780I1145J718D01*
G03X381656Y186218I196J-349D01*
G02X381808Y185120I-1146J-718D01*
G03X382102Y184618I384J-112D01*
G02X382935Y184034I-303J-1318D01*
G03X383586Y184004I336J217D01*
G02X383890Y184288I1064J-834D01*
G03X383878Y184957I-225J331D01*
G02X383836Y187215I722J1143D01*
G03X383860Y187857I-226J330D01*
G02X384027Y190078I848J1053D01*
G03X384021Y190772I-202J345D01*
G02X385365Y190782I663J1178D01*
G03X385371Y190088I202J-345D01*
G02X385472Y187795I-663J-1178D01*
G03X385448Y187153I226J-330D01*
G02X385360Y184982I-848J-1053D01*
G03X385372Y184313I225J-331D01*
G02X385321Y181996I-722J-1143D01*
G03X385342Y181291I199J-347D01*
G02X383543Y179451I-602J-1211D01*
G03X382854Y179483I-354J-186D01*
G02X381857Y178875I-1133J737D01*
G03X381588Y178224I41J-398D01*
G37*
G36*
G01X377542Y176789D02*
G02X376095Y176775I-712J-1149D01*
G03X376088Y177451I-217J336D01*
G02X376033Y179713I712J1149D01*
G03X376020Y180381I-227J330D01*
G02X377509Y180411I722J1143D01*
G03X377522Y179743I227J-330D01*
G02X377535Y177465I-722J-1143D01*
G03X377542Y176789I217J-336D01*
G37*
G36*
G01X368687Y169664D02*
G02X367240Y169618I-687J-1164D01*
G03X367219Y170294I-224J331D01*
G02X369005Y172245I687J1164D01*
G03X369689Y172300I325J233D01*
G02X371670Y170589I1211J-600D01*
G03X371716Y169904I228J-329D01*
G02X370330Y169811I-615J-1204D01*
G03X370284Y170496I-228J329D01*
G02X369801Y170913I617J1203D01*
G03X369117Y170858I-325J-233D01*
G02X368666Y170340I-1212J600D01*
G03X368687Y169664I224J-331D01*
G37*
G36*
G01X384277Y169528D02*
G02X382348Y167767I-729J-1138D01*
G03X381652Y167792I-355J-184D01*
G02X381700Y169123I-1152J708D01*
G03X382396Y169098I355J184D01*
G02X382931Y169593I1152J-708D01*
G03X382964Y170286I-183J356D01*
G02X384310Y170221I730J1138D01*
G03X384277Y169528I183J-356D01*
G37*
G36*
G01X350319Y125555D02*
G03X350216Y124971I213J-339D01*
G02X348430Y125286I-1067J-830D01*
G03X348533Y125870I-213J339D01*
G02X350319Y125555I1067J830D01*
G37*
G36*
G01X342118Y113562D02*
G03X342659Y113560I272J293D01*
G02X342652Y111568I911J-999D01*
G03X342111Y111570I-272J-293D01*
G02X342118Y113562I-911J999D01*
G37*
G36*
G01X352155Y113078D02*
G03X352077Y112517I241J-319D01*
G02X350187Y112780I-1077J-817D01*
G03X350265Y113341I-241J319D01*
G02X352155Y113078I1077J817D01*
G37*
G36*
G01X362865Y104684D02*
G03X362485Y104242I18J-400D01*
G02X361079Y105450I-1344J-143D01*
G03X361459Y105892I-18J400D01*
G02X362865Y104684I1344J143D01*
G37*
G36*
G01X381145Y147695D02*
G02X379747Y147753I-747J-1127D01*
G03X379775Y148437I-193J350D01*
G02X379320Y148946I748J1126D01*
G03X378624Y148974I-356J-183D01*
G02X378678Y150306I-1148J714D01*
G03X379374Y150278I356J183D01*
G02X381692Y150242I1148J-714D01*
G03X382389Y150251I346J201D01*
G02X384240Y148426I1186J-648D01*
G03X384234Y147733I197J-348D01*
G02X382883Y147745I-686J-1165D01*
G03X382889Y148438I-197J348D01*
G02X382405Y148925I686J1165D01*
G03X381708Y148916I-346J-201D01*
G02X381173Y148379I-1187J647D01*
G03X381145Y147695I193J-350D01*
G37*
G36*
G01X362346Y147737D02*
G02X360900Y147639I-646J-1188D01*
G03X360854Y148312I-237J322D01*
G02X362300Y148410I646J1188D01*
G03X362346Y147737I237J-322D01*
G37*
G36*
G01X368659Y144613D02*
G02X367373Y144602I-633J-1195D01*
G03X367367Y145305I-194J350D01*
G02X368653Y145316I633J1195D01*
G03X368659Y144613I194J-350D01*
G37*
G36*
G01X382265Y144048D02*
G02X382212Y142651I1130J-742D01*
G03X381528Y142676I-350J-194D01*
G02X381581Y144073I-1130J742D01*
G03X382265Y144048I350J194D01*
G37*
G36*
G01X388062Y142444D02*
G02X388037Y144147I-1062J836D01*
G03X388659Y144156I307J256D01*
G02X388684Y142453I1062J-836D01*
G03X388062Y142444I-307J-256D01*
G37*
G36*
G01X362394Y141444D02*
G02X361038Y141432I-668J-1176D01*
G03X361032Y142124I-203J344D01*
G02X362820Y144057I668J1176D01*
G03X363487Y144064I331J224D01*
G02X365372Y142203I1134J-737D01*
G03X365432Y141505I222J-333D01*
G02X364135Y141393I-547J-1237D01*
G03X364075Y142091I-222J333D01*
G02X363501Y142571I546J1237D01*
G03X362834Y142564I-331J-224D01*
G02X362388Y142136I-1134J736D01*
G03X362394Y141444I203J-344D01*
G37*
G36*
G01X372366Y136249D02*
G02X372319Y137612I-1190J641D01*
G03X373010Y137635I339J213D01*
G02X373057Y136272I1190J-641D01*
G03X372366Y136249I-339J-213D01*
G37*
G36*
G01X365317Y135203D02*
G02X364006Y135160I-617J-1203D01*
G03X363983Y135860I-205J344D01*
G02X365294Y135903I617J1203D01*
G03X365317Y135203I205J-344D01*
G37*
G36*
G01X381067Y135104D02*
G02X379791Y135135I-667J-1176D01*
G03X379808Y135840I-180J357D01*
G02X381652Y137682I667J1176D01*
G03X382358Y137700I348J197D01*
G02X382390Y136430I1209J-605D01*
G03X381684Y136412I-348J-197D01*
G02X381084Y135809I-1210J604D01*
G03X381067Y135104I180J-357D01*
G37*
G36*
G01X378374Y122240D02*
G02X377119Y122276I-662J-1179D01*
G03X377139Y122984I-176J359D01*
G02X378394Y122948I662J1179D01*
G03X378374Y122240I176J-359D01*
G37*
G36*
G01X339467Y117913D02*
G02X338069I-699J-1158D01*
G03Y118597I-206J342D01*
G02X339467I699J1158D01*
G03Y117913I206J-342D01*
G37*
G36*
G01X347295Y116321D02*
G02X345897I-699J-1158D01*
G03Y117005I-206J342D01*
G02X345860Y119297I699J1158D01*
G03X345861Y119968I-217J336D01*
G02X347336Y119966I739J1132D01*
G03X347335Y119295I217J-336D01*
G02X347295Y117005I-739J-1132D01*
G03Y116321I206J-342D01*
G37*
G36*
G01X370781Y114808D02*
G02X369215Y114809I-784J-1102D01*
G03X369216Y115461I-231J326D01*
G02X369341Y117744I784J1102D01*
G03X369364Y118429I-194J349D01*
G02Y120697I736J1134D01*
G03X369341Y121382I-217J336D01*
G02X368978Y121678I660J1180D01*
G03X368366Y121670I-303J-261D01*
G02X366525Y123621I-1045J858D01*
G03X366502Y124283I-236J323D01*
G02X368314Y126224I719J1145D01*
G03X368976Y126247I323J236D01*
G02X371131Y126427I1145J-719D01*
G03X371747Y126450I299J266D01*
G02X371811Y124729I1074J-822D01*
G03X371195Y124706I-299J-266D01*
G02X370793Y124355I-1073J823D01*
G03X370765Y123678I198J-347D01*
G02X370736Y121429I-765J-1115D01*
G03X370759Y120744I217J-336D01*
G02X371068Y120506I-662J-1179D01*
G03X371662Y120529I287J279D01*
G02X371732Y118720I1038J-866D01*
G03X371138Y118697I-287J-279D01*
G02X370759Y118382I-1039J865D01*
G03X370736Y117697I194J-349D01*
G02X370782Y115460I-736J-1134D01*
G03X370781Y114808I231J-326D01*
G37*
G36*
G01X378539Y113195D02*
G02X377074Y113204I-739J-1132D01*
G03X377079Y113876I-214J338D01*
G02X378544Y113867I739J1132D01*
G03X378539Y113195I214J-338D01*
G37*
G36*
G01X513224Y255092D02*
G03X512654Y255062I-270J-295D01*
G02X512553Y256953I-1014J894D01*
G03X513123Y256983I270J295D01*
G02X513224Y255092I1014J-894D01*
G37*
G36*
G01X475512Y42074D02*
X460314D01*
G02Y48478I-2401J3202D01*
G01X475512D01*
G02Y42074I2401J-3202D01*
G37*
G36*
G01X674533Y272063D02*
G03X673939Y271972I-257J-307D01*
G02X673667Y273737I-1139J728D01*
G03X674261Y273828I257J307D01*
G02X674533Y272063I1139J-728D01*
G37*
G36*
G01X745863Y271858D02*
G03X745284Y271792I-258J-305D01*
G02X745074Y273631I-1084J808D01*
G03X745653Y273697I258J305D01*
G02X745863Y271858I1084J-808D01*
G37*
G36*
G01X660852Y274013D02*
G03X661331Y273625I400J4D01*
G02X660248Y272287I269J-1325D01*
G03X659769Y272675I-400J-4D01*
G02X660852Y274013I-269J1325D01*
G37*
G36*
G01X721148Y271310D02*
G03X720918Y271835I-371J151D01*
G02X722647Y272590I477J1265D01*
G03X722877Y272065I371J-151D01*
G02X721148Y271310I-477J-1265D01*
G37*
G36*
G01X701545Y272574D02*
G03X701774Y272043I369J-156D01*
G02X700055Y271303I-474J-1266D01*
G03X699826Y271834I-369J156D01*
G02X701545Y272574I474J1266D01*
G37*
G36*
G01X741112Y272361D02*
G03X741423Y271833I377J-133D01*
G02X739926Y270952I-223J-1333D01*
G03X739615Y271480I-377J133D01*
G02X741112Y272361I223J1333D01*
G37*
G36*
G01X713582Y271737D02*
G03X713377Y271166I143J-374D01*
G02X711718Y271763I-1177J-666D01*
G03X711923Y272334I-143J374D01*
G02X713582Y271737I1177J666D01*
G37*
G36*
G01X707382D02*
G03X707177Y271166I143J-374D01*
G02X704775Y271073I-1177J-666D01*
G03X704382Y271641I-362J169D01*
G02X705285Y273890I-105J1348D01*
G03X705884Y273892I299J266D01*
G02X708012Y273769I1016J-892D01*
G03X708583Y273677I329J227D01*
G02X708288Y271831I817J-1077D01*
G03X707717Y271923I-329J-227D01*
G02X707382Y271737I-817J1077D01*
G37*
G36*
G01X739750Y263770D02*
G03X739599Y263206I188J-353D01*
G02X737814Y263681I-1146J-717D01*
G03X737965Y264245I-188J353D01*
G02X739750Y263770I1146J717D01*
G37*
G36*
G01X720115Y263690D02*
G03X720267Y264263I-184J355D01*
G02X722022Y263799I1134J737D01*
G03X721870Y263226I184J-355D01*
G02X720115Y263690I-1134J-737D01*
G37*
G36*
G01X717927Y264261D02*
G03X718077Y263688I335J-218D01*
G02X716320Y263228I-625J-1199D01*
G03X716170Y263801I-335J218D01*
G02X717927Y264261I625J1199D01*
G37*
G36*
G01X700822Y263700D02*
G03X700657Y263149I184J-355D01*
G02X698855Y263689I-1180J-660D01*
G03X699020Y264240I-184J355D01*
G02X700822Y263700I1180J660D01*
G37*
G36*
G01X696639Y264271D02*
G03X696797Y263698I337J-215D01*
G02X695053Y263218I-605J-1209D01*
G03X694895Y263791I-337J215D01*
G02X696639Y264271I605J1209D01*
G37*
G36*
G01X674970Y263212D02*
G03X674807Y263785I-338J214D01*
G02X676543Y264277I593J1215D01*
G03X676706Y263704I338J-214D01*
G02X674970Y263212I-593J-1215D01*
G37*
G36*
G01X653595Y263686D02*
G03X653420Y263136I176J-359D01*
G02X651638Y263703I-1187J-647D01*
G03X651813Y264253I-176J359D01*
G02X653595Y263686I1187J647D01*
G37*
G36*
G01X731284Y256973D02*
G03X731307Y256402I291J-274D01*
G02X729416Y256327I-907J-1002D01*
G03X729393Y256898I-291J274D01*
G02X731284Y256973I907J1002D01*
G37*
G36*
G01X712606Y254462D02*
G03X712823Y253906I357J-181D01*
G02X711144Y253250I-473J-1266D01*
G03X710927Y253806I-357J181D01*
G02X712606Y254462I473J1266D01*
G37*
G36*
G01X674993Y254175D02*
G03X675190Y253639I361J-171D01*
G02X673413Y252983I-554J-1233D01*
G03X673216Y253519I-361J171D01*
G02X674993Y254175I554J1233D01*
G37*
G36*
G01X684523Y253244D02*
G03X684525Y253861I-254J309D01*
G02X684391Y253989I865J1039D01*
G03X683799I-296J-269D01*
G02X683316Y253650I-1000J911D01*
G03X683110Y253102I152J-370D01*
G02X681384Y253750I-1211J-602D01*
G03X681590Y254298I-152J370D01*
G02X683799Y255811I1211J602D01*
G03X684391I296J269D01*
G02X686249Y253856I999J-911D01*
G03X686247Y253239I254J-309D01*
G02X684523Y253244I-865J-1039D01*
G37*
G36*
G01X705056Y253804D02*
G03X705065Y253209I272J-293D01*
G02X703259Y253181I-887J-1020D01*
G03X703250Y253776I-272J293D01*
G02X703081Y253951I884J1023D01*
G03X702513Y254009I-312J-249D01*
G02X700723Y256034I-864J1040D01*
G03X700736Y256605I-273J292D01*
G02X702630Y256564I968J944D01*
G03X702617Y255993I273J-292D01*
G02X702705Y255894I-965J-947D01*
G03X703273Y255836I312J249D01*
G02X705056Y253804I864J-1040D01*
G37*
G36*
G01X666314Y253806D02*
G03X666360Y253232I300J-265D01*
G02X664486Y253083I-860J-1043D01*
G03X664440Y253657I-300J265D01*
G02X666314Y253806I860J1043D01*
G37*
G36*
G01X671012Y253619D02*
G03X670950Y253037I240J-320D01*
G02X669118Y253231I-1020J-887D01*
G03X669180Y253813I-240J320D01*
G02X671012Y253619I1020J887D01*
G37*
G36*
G01X689712Y253601D02*
G03X689693Y253028I269J-296D01*
G02X687808Y253089I-974J-938D01*
G03X687827Y253662I-269J296D01*
G02X688433Y255901I973J938D01*
G03X688707Y256404I-108J385D01*
G02X691283Y257225I1293J396D01*
G03X691797Y256974I380J126D01*
G02X690967Y255275I453J-1274D01*
G03X690453Y255526I-380J-126D01*
G02X690367Y255499I-448J1276D01*
G03X690093Y254996I108J-385D01*
G02X689712Y253601I-1293J-396D01*
G37*
G36*
G01X789242Y181833D02*
G03X789259Y181550I149J-133D01*
G02X786158Y181367I-1459J-1650D01*
G03X786141Y181650I-149J133D01*
G02X785762Y184512I1459J1649D01*
G01X785852Y184648D01*
X782500Y188000D01*
Y204000D01*
X786000Y207500D01*
Y220000D01*
X788000Y222000D01*
X791000D01*
X792500Y220500D01*
Y208500D01*
X793000Y208000D01*
X795000D01*
X796500Y206500D01*
Y203000D01*
X796000Y202500D01*
Y195000D01*
X801500Y189500D01*
Y186000D01*
X800000Y184500D01*
X790076D01*
G03X789695Y183977I0J-400D01*
G02X789242Y181833I-2095J-677D01*
G37*
G36*
G01X811273Y158919D02*
G03X811258Y158386I291J-275D01*
G02X807827Y158481I-1758J-1486D01*
G03X807842Y159014I-291J275D01*
G02X808007Y162162I1758J1486D01*
G03X808022Y162724I-277J289D01*
G02X811293Y162638I1678J1576D01*
G03X811278Y162076I277J-289D01*
G02X811273Y158919I-1678J-1576D01*
G37*
G36*
G01X812548Y132296D02*
G03Y131704I269J-296D01*
G02X809452I-1548J-1704D01*
G03Y132296I-269J296D01*
G02Y135704I1548J1704D01*
G03Y136296I-269J296D01*
G02X809373Y139629I1548J1704D01*
G03X809403Y140162I-282J283D01*
G02X812827Y139971I1798J1438D01*
G03X812797Y139438I282J-283D01*
G02X812548Y136296I-1797J-1438D01*
G03Y135704I269J-296D01*
G02Y132296I-1548J-1704D01*
G37*
G36*
G01X693707Y272312D02*
G02X693653Y273752I-1170J677D01*
G03X694330Y273777I331J225D01*
G02X694384Y272337I1170J-677D01*
G03X693707Y272312I-331J-225D01*
G37*
G36*
G01X645377Y270007D02*
G02X642952Y271151I-1287J413D01*
G03X642689Y271760I-336J216D01*
G02X644075Y272358I249J1329D01*
G03X644338Y271749I336J-216D01*
G02X644554Y271690I-247J-1329D01*
G03X645073Y271943I138J375D01*
G02X646502Y272875I1288J-413D01*
G03X646943Y273242I42J398D01*
G02X648149Y271795I1348J-102D01*
G03X647708Y271428I-42J-398D01*
G02X645896Y270260I-1348J102D01*
G03X645377Y270007I-138J-375D01*
G37*
G36*
G01X638096Y271184D02*
G02X636518Y271211I-808J-1084D01*
G03X636529Y271860I-228J328D01*
G02X638107Y271833I808J1084D01*
G03X638096Y271184I228J-328D01*
G37*
G36*
G01X605864Y271216D02*
G02X604309Y271197I-764J-1116D01*
G03X604301Y271851I-234J324D01*
G02X605856Y271870I764J1116D01*
G03X605864Y271216I234J-324D01*
G37*
G36*
G01X665542Y270862D02*
G02X663921Y271222I-1042J-862D01*
G03X664058Y271838I-171J361D01*
G02X666170Y273527I1042J862D01*
G03X666832Y273570I317J245D01*
G02X669339Y272706I1168J-681D01*
G03X669728Y272252I396J-54D01*
G02X668361Y271084I-28J-1352D01*
G03X667972Y271538I-396J54D01*
G02X666930Y272063I28J1352D01*
G03X666268Y272020I-317J-245D01*
G02X665679Y271478I-1169J679D01*
G03X665542Y270862I171J-361D01*
G37*
G36*
G01X731073Y269212D02*
G02X729439Y271095I-1213J598D01*
G03X729562Y271789I-125J380D01*
G02X729414Y271925I838J1061D01*
G03X728821Y271913I-291J-274D01*
G02X726835Y271853I-1021J887D01*
G03X726265I-285J-281D01*
G02Y273747I-965J947D01*
G03X726835I285J281D01*
G02X728786Y273725I965J-947D01*
G03X729379Y273737I291J274D01*
G02X730821Y271565I1021J-887D01*
G03X730698Y270871I125J-380D01*
G02X730870Y270709I-837J-1061D01*
G03X731527Y270798I299J266D01*
G02X731730Y269301I1213J-598D01*
G03X731073Y269212I-299J-266D01*
G37*
G36*
G01X691546Y270605D02*
G02X690556Y269153I354J-1305D01*
G03X690054Y269495I-397J-44D01*
G02X688377Y271081I-354J1305D01*
G03X687917Y271558I-391J83D01*
G02X686612Y272063I-235J1331D01*
G03X686022Y272111I-317J-244D01*
G02X686170Y273926I-922J989D01*
G03X686760Y273878I317J244D01*
G02X689005Y272608I922J-989D01*
G03X689465Y272131I391J-83D01*
G02X691044Y270947I235J-1331D01*
G03X691546Y270605I397J44D01*
G37*
G36*
G01X683668Y269227D02*
G02X682054Y268857I-568J-1227D01*
G03X681913Y269473I-309J253D01*
G02X683527Y269843I568J1227D01*
G03X683668Y269227I309J-253D01*
G37*
G36*
G01X735564Y263782D02*
G02X734025Y263211I-396J-1293D01*
G03X733804Y263807I-338J214D01*
G02X735343Y264378I396J1293D01*
G03X735564Y263782I338J-214D01*
G37*
G36*
G01X680602Y263103D02*
G02X679121Y263812I-1204J-614D01*
G03X679396Y264386I-81J392D01*
G02X680877Y263677I1204J614D01*
G03X680602Y263103I81J-392D01*
G37*
G36*
G01X649388Y263767D02*
G02X647931Y263380I-440J-1278D01*
G03X647760Y264022I-301J264D01*
G02X649217Y264409I440J1278D01*
G03X649388Y263767I301J-264D01*
G37*
G36*
G01X708462Y253250D02*
G02X706757Y253446I-972J-940D01*
G03X706828Y254060I-217J336D01*
G02X708533Y253864I972J940D01*
G03X708462Y253250I217J-336D01*
G37*
G36*
G01X733496Y251816D02*
G02X733016Y253278I-1296J384D01*
G03X733641Y253484I241J319D01*
G02X734121Y252022I1296J-384D01*
G03X733496Y251816I-241J-319D01*
G37*
G36*
G01X745192Y253311D02*
G02X743422Y253082I-755J-1122D01*
G03X743345Y253678I-300J264D01*
G02X743047Y253952I756J1121D01*
G03X742467Y253998I-312J-251D01*
G02X741469Y253651I-908J1002D01*
G03X741056Y253149I-26J-399D01*
G02X739841Y254149I-1306J-349D01*
G03X740254Y254651I26J399D01*
G02X742613Y255848I1306J349D01*
G03X743193Y255802I312J251D01*
G02X745115Y253907I907J-1002D01*
G03X745192Y253311I300J-264D01*
G37*
G36*
G01X643817Y253080D02*
G02X641956Y253240I-1014J-894D01*
G03X642005Y253816I-251J311D01*
G02X644281Y255197I1015J894D01*
G03X644943Y255065I373J144D01*
G02X647270Y254066I977J-935D01*
G03X647700Y253648I400J-19D01*
G02X646450Y252364I100J-1348D01*
G03X646020Y252782I-400J19D01*
G02X644659Y253643I-100J1348D01*
G03X643997Y253775I-373J-144D01*
G02X643866Y253656I-973J939D01*
G03X643817Y253080I251J-311D01*
G37*
G36*
G01X722234Y253235D02*
G02X720637Y253295I-839J-1060D01*
G03X720661Y253940I-224J331D01*
G02X720593Y256002I839J1060D01*
G03X720616Y256573I-268J297D01*
G02X722507Y256498I984J927D01*
G03X722484Y255927I268J-297D01*
G02X722734Y255553I-983J-928D01*
G03X723390Y255442I365J163D01*
G02X725717Y254362I984J-927D01*
G03X726077Y253919I398J-45D01*
G02X724607Y252726I-127J-1346D01*
G03X724247Y253169I-398J45D01*
G02X723140Y253962I127J1346D01*
G03X722484Y254073I-365J-163D01*
G02X722258Y253880I-986J925D01*
G03X722234Y253235I224J-331D01*
G37*
G36*
G01X660760Y246667D02*
G02X659474Y247740I-1323J-278D01*
G03X659877Y248222I11J400D01*
G02X661163Y247149I1323J278D01*
G03X660760Y246667I-11J-400D01*
G37*
G36*
G01X789391Y13017D02*
G02X788201Y11112I1109J-2017D01*
G03X787609Y11483I-400J20D01*
G02X788799Y13388I-1109J2017D01*
G03X789391Y13017I400J-20D01*
G37*
G36*
G01X688597Y186283D02*
G03X688714Y185751I345J-203D01*
G02X685559Y185061I-1258J-1807D01*
G03X685442Y185593I-345J203D01*
G02X688597Y186283I1258J1807D01*
G37*
G36*
G01X726636Y174731D02*
G03X726114Y174642I-211J-340D01*
G02X725564Y177894I-1714J1383D01*
G03X726086Y177983I211J340D01*
G02X726636Y174731I1714J-1383D01*
G37*
G36*
G01X691020Y177409D02*
G03X691032Y177126I147J-136D01*
G02X687927Y176991I-1485J-1626D01*
G03X687915Y177274I-147J136D01*
G02X691020Y177409I1485J1626D01*
G37*
G36*
G01X753461Y117775D02*
G03X753876Y117298I392J-78D01*
G02X751839Y115525I123J-2198D01*
G03X751424Y116002I-392J78D01*
G02X751380Y115999I-172J2195D01*
G03X750995Y115631I14J-400D01*
G02X748720Y118001I-2195J169D01*
G03X749105Y118369I-14J400D01*
G02X753461Y117775I2195J-169D01*
G37*
G36*
G01X760603Y105665D02*
G03X760885Y105641I153J129D01*
G02X760617Y102542I1419J-1684D01*
G03X760335Y102566I-153J-129D01*
G02X760603Y105665I-1419J1684D01*
G37*
G36*
G01X768668Y139043D02*
G02X768510Y140896I-2068J757D01*
G03X769232Y140957I347J199D01*
G02X769390Y139104I2068J-757D01*
G03X768668Y139043I-347J-199D01*
G37*
G54D30*
X37600Y203700D03*
X40400Y207800D03*
G54D38*
X753000Y272100D03*
G54D37*
X538300Y15200D03*
G54D28*
X14400Y98000D03*
X14500Y198000D03*
X129500Y252500D03*
X129000Y268000D03*
X166500Y241000D03*
X732000Y63500D03*
X770500Y13007D03*
X759000Y37507D03*
X769500Y234500D03*
X769400Y252700D03*
X785500Y8000D03*
G54D31*
X296811Y263386D03*
G54D29*
X17500Y190200D03*
X16844Y203100D03*
X17301Y212401D03*
X17300Y218307D03*
X16400Y224212D03*
X21900Y205400D03*
X41200Y90300D03*
X42000Y96000D03*
X62900Y79900D03*
X227000Y275500D03*
X40500Y124300D03*
X53500Y120400D03*
X57600Y136900D03*
X58000Y141750D03*
X58800Y177000D03*
X69235Y99735D03*
X90500Y101000D03*
X86100Y97700D03*
X86500Y113500D03*
X80500D03*
X57287Y219806D03*
X97100Y189200D03*
X131500Y149000D03*
X150804Y158896D03*
X158500Y161820D03*
X181000Y167500D03*
X75300Y259900D03*
X82100Y259600D03*
X88900Y246700D03*
X110166Y239500D03*
X104900Y248800D03*
X97600Y246500D03*
X109500Y258300D03*
X112700Y231400D03*
X146000Y231000D03*
X146500Y236500D03*
X155300Y254000D03*
X165700D03*
X195000Y234000D03*
X206000D03*
X146980Y200580D03*
X153000Y201900D03*
X174739Y207381D03*
X304300Y262900D03*
X236700Y88500D03*
X694600Y229800D03*
X727400Y227400D03*
X738000Y65700D03*
X752500Y49007D03*
X793000Y174500D03*
X805500Y128000D03*
X701245Y183800D03*
X725500Y195500D03*
X742100Y118200D03*
X740300Y164700D03*
X733000Y176200D03*
X757900Y124700D03*
X743100Y195500D03*
X765500Y112000D03*
X759400Y131000D03*
X769800Y133000D03*
G54D32*
X368100Y162200D03*
X364600Y171600D03*
X369021Y180128D03*
X369450Y212040D03*
X371100Y199500D03*
X365250Y208600D03*
X372700Y213700D03*
X369580Y215400D03*
X372800Y221600D03*
X369580Y218800D03*
X377500Y165240D03*
X374100Y159150D03*
X380477Y171605D03*
X386600Y174900D03*
X381280Y191550D03*
X382471Y199843D03*
X385900Y222600D03*
X372950Y217400D03*
X385900Y218400D03*
X382600Y222600D03*
X385947Y226500D03*
X392100Y213700D03*
X395700Y213600D03*
X392000Y217200D03*
X395700Y220600D03*
X395600Y224400D03*
X391950Y220800D03*
X395700Y217000D03*
X399700Y216400D03*
X389100Y224000D03*
X339500Y102000D03*
X344500Y94000D03*
X344523Y98477D03*
X347230Y100190D03*
X348076Y108910D03*
X355175Y108212D03*
X354333Y125665D03*
X364800Y91200D03*
X361200Y90200D03*
X368600Y90700D03*
X371900Y89000D03*
Y85400D03*
X368600Y97500D03*
X357721Y91779D03*
X361200Y97500D03*
X371950Y92500D03*
X368600Y94100D03*
X365000Y94700D03*
X360900Y94200D03*
X357721Y95100D03*
X364874Y98250D03*
X357900Y99200D03*
X358000Y115500D03*
X366400Y112200D03*
X365721Y115528D03*
X368721Y108528D03*
X359942Y110924D03*
X365316Y108130D03*
X358500Y137000D03*
X367121Y128628D03*
X362111Y130128D03*
X368026Y137118D03*
X367992Y133982D03*
X368026Y140268D03*
X380443Y130102D03*
X381500Y123200D03*
X381600Y126427D03*
X374200Y149494D03*
Y143294D03*
X380400Y152700D03*
X374200Y140144D03*
X393000Y140268D03*
X526715Y254700D03*
X522908Y255117D03*
X511736Y273001D03*
X525845Y272863D03*
X521131Y262489D03*
X517846D03*
X522992Y270700D03*
X514900Y271350D03*
X541005Y254800D03*
X531775Y252231D03*
X530015Y255000D03*
X541500Y270900D03*
X530900Y273000D03*
X538847Y262489D03*
X535562D03*
X534100Y270700D03*
X550200Y255500D03*
X544800Y255100D03*
X551000Y252056D03*
X548800Y271000D03*
X555641Y262489D03*
X551937Y272789D03*
X544292Y273128D03*
X565054Y254773D03*
X571867Y254685D03*
X561419Y254850D03*
X568327Y253348D03*
X564100Y271100D03*
X558926Y262489D03*
X567800Y270500D03*
X560600Y270300D03*
X570200Y273100D03*
X579205Y254850D03*
X582200Y252206D03*
X573357Y262489D03*
X580200Y273000D03*
X576642Y262489D03*
X504000Y12507D03*
X508700Y14607D03*
X511589Y30295D03*
X507839Y30362D03*
X523453Y12360D03*
X511800Y12507D03*
X520700Y14807D03*
X518769Y22907D03*
X515484D03*
X522733Y32832D03*
X525753Y30893D03*
X528525Y12549D03*
X530700Y15407D03*
X542100Y15107D03*
X536485Y22907D03*
X533200D03*
X542407Y30882D03*
X532350Y30807D03*
X529120Y32575D03*
X544860Y12407D03*
X550000Y12507D03*
X552800Y14807D03*
X554460Y22907D03*
X557745D03*
X553079Y30712D03*
X549500Y31607D03*
X545928Y31047D03*
X568555Y12407D03*
X561200Y12507D03*
X571600Y14207D03*
X564400Y14307D03*
X570852Y33204D03*
X561456Y30902D03*
X569800Y29807D03*
X565091Y30815D03*
X587940Y12417D03*
X582655Y12407D03*
X577824Y22907D03*
X579800Y14807D03*
X574539Y22907D03*
X581450Y30707D03*
X585179Y30867D03*
X594600Y6707D03*
X601704Y22907D03*
X589300Y33007D03*
X594400Y36207D03*
X607300Y14507D03*
X604989Y22907D03*
X607800Y30407D03*
X644550Y267170D03*
X653600Y252130D03*
X653041Y272989D03*
X680400Y273100D03*
X693860Y252210D03*
X699800Y252230D03*
X716737Y252189D03*
Y272989D03*
X715900Y270000D03*
X734510Y273110D03*
X749000Y252200D03*
X634555Y25307D03*
X634757Y20207D03*
X627255Y25107D03*
X627231Y19907D03*
X630955Y25207D03*
X631000Y20107D03*
X638400Y20607D03*
X638290Y25674D03*
G54D36*
X502500Y6200D03*
X809000Y149200D03*
X756400Y110500D03*
X782000Y137000D03*
G54D34*
X496711Y248999D03*
G54D33*
X492520Y262598D03*
X761417Y22798D03*
G54D35*
X498425D03*
X755512Y262598D03*
G54D26*
X11500Y68500D03*
G54D27*
X45669Y77185D03*
Y172460D03*
%LPD*%
G75*
G36*
G01X788500Y220500D02*
X790500D01*
X791000Y220000D01*
Y208000D01*
X792500Y206500D01*
X794000D01*
X795000Y205500D01*
Y204000D01*
X794500Y203500D01*
Y194000D01*
X800000Y188500D01*
Y187000D01*
X799000Y186000D01*
X786500D01*
X784000Y188500D01*
Y203500D01*
X787500Y207000D01*
Y219500D01*
X788500Y220500D01*
G37*
G54D10*
X15400Y118000D03*
X10900D03*
X15500Y122800D03*
X15000Y127500D03*
X11000Y122800D03*
X10500Y127500D03*
X11500Y163700D03*
Y159000D03*
X7000Y163700D03*
Y159000D03*
X45500Y118000D03*
X37500Y264000D03*
X63500Y43500D03*
Y57500D03*
Y48000D03*
Y52500D03*
X50500Y160000D03*
X68500Y47500D03*
X73500Y48000D03*
X68000Y52500D03*
X95500Y93500D03*
X92800Y285600D03*
X99500Y91500D03*
Y96000D03*
X104000Y92000D03*
Y96500D03*
Y115500D03*
X97500Y285450D03*
X102000D03*
X106500Y285550D03*
X110700D03*
X113200Y146700D03*
X113100Y151000D03*
X117500Y146950D03*
X119000Y159100D03*
X114700Y158800D03*
X122250Y228750D03*
Y233000D03*
Y237300D03*
Y241500D03*
X133941Y208863D03*
X131003Y205766D03*
X138100Y208100D03*
X136500Y272500D03*
X192500Y161900D03*
X192600Y166700D03*
X203100Y252900D03*
X207500Y253000D03*
X217000Y252900D03*
X217200Y258000D03*
X221300Y255400D03*
X240130Y77300D03*
X236400Y95100D03*
X278200Y281350D03*
X282686Y281336D03*
X335700Y278751D03*
X331500D03*
X353500Y71900D03*
X357000Y69500D03*
X349300Y83000D03*
X345100D03*
X354200Y76400D03*
X343600Y270500D03*
X359800Y72700D03*
X362700Y69600D03*
X443800Y246100D03*
X474000Y9000D03*
X467200Y4400D03*
X481500Y8900D03*
X489600Y8800D03*
X497100D03*
X659811Y260757D03*
X657500Y258400D03*
X661308Y263698D03*
X655500Y270500D03*
X657787Y264179D03*
X656000Y261400D03*
X655523Y266616D03*
X658667Y267622D03*
X710200Y201700D03*
X721200Y65100D03*
X753500Y24007D03*
Y20007D03*
Y28507D03*
X755500Y16000D03*
X767500Y24007D03*
X760500Y29000D03*
X761000Y16007D03*
X767500Y28507D03*
Y19507D03*
X764200Y44200D03*
X767500Y33207D03*
X764500Y54000D03*
X764300Y49200D03*
X769500Y50000D03*
X761000Y58500D03*
X763600Y168000D03*
X764000Y188000D03*
Y197500D03*
Y192810D03*
Y202310D03*
X774300Y102500D03*
X778500D03*
Y107000D03*
X774300D03*
X783000Y113000D03*
Y118500D03*
Y123000D03*
X785830Y188700D03*
X785400Y202800D03*
X789000Y204979D03*
X789200Y214200D03*
Y209800D03*
X784500Y222500D03*
X789000Y223500D03*
X789200Y218700D03*
X786000Y228000D03*
Y232400D03*
X786200Y236900D03*
X786300Y241500D03*
X785000Y245800D03*
Y250200D03*
Y254900D03*
X789910Y187679D03*
X794110D03*
X798310Y187779D03*
X793500Y204979D03*
Y223500D03*
X793200Y228400D03*
Y232600D03*
Y237200D03*
Y242400D03*
X793300Y247200D03*
X795300Y260800D03*
X795400Y251700D03*
X795300Y256500D03*
Y265000D03*
X810100Y275000D03*
X812035Y271067D03*
X810100Y267339D03*
X812000Y263500D03*
G54D20*
G01X356600Y195700D02*
X355875Y196425D01*
Y197892D01*
X357150Y199167D01*
Y209150D01*
X356200Y210100D01*
Y214032D01*
X349332Y220900D01*
X344632D01*
X339405Y226127D01*
Y226480D01*
G01X338486Y225560D02*
X338522Y225524D01*
X338876D01*
X344300Y220100D01*
X349000D01*
X351249Y217851D01*
Y217300D01*
X352097Y216451D01*
X352649D01*
X355400Y213700D01*
Y209768D01*
X356350Y208818D01*
Y207618D01*
X355960Y207228D01*
Y206028D01*
X356350Y205638D01*
Y204438D01*
X355960Y204048D01*
Y202848D01*
X356350Y202458D01*
Y199499D01*
X355075Y198224D01*
Y194925D01*
X356700Y193300D01*
G01X353625Y195045D02*
X352959Y195711D01*
Y207091D01*
X350150Y209900D01*
Y215350D01*
X346500Y219000D01*
X343400D01*
X338100Y224300D01*
X334746D01*
X334395Y224651D01*
Y225005D01*
X334013Y225387D01*
G01X349100Y191900D02*
X349017D01*
X348096Y192821D01*
Y203904D01*
X342300Y209700D01*
Y211932D01*
X340400Y213832D01*
Y218732D01*
X337132Y222000D01*
X332886D01*
X331438Y223448D01*
Y223798D01*
X331439Y223799D01*
Y223800D01*
X331368Y223871D01*
G01X353625Y192045D02*
X352159Y193511D01*
Y202296D01*
X351769Y202686D01*
Y203886D01*
X352159Y204276D01*
Y206759D01*
X349350Y209568D01*
Y215018D01*
X346168Y218200D01*
X343068D01*
X337768Y223500D01*
X334414D01*
X333446Y224468D01*
X333093D01*
G01X345503Y193474D02*
X344853Y194124D01*
Y198658D01*
X342950Y200561D01*
Y201382D01*
X335300Y209032D01*
Y215532D01*
X327277Y223555D01*
Y223909D01*
X327207Y223979D01*
G01X349100Y189700D02*
X347296Y191504D01*
Y195834D01*
X346906Y196224D01*
Y197424D01*
X347296Y197814D01*
Y203572D01*
X341500Y209368D01*
Y211600D01*
X339600Y213500D01*
Y218400D01*
X336800Y221200D01*
X332554D01*
X330874Y222880D01*
X330520D01*
X330449Y222951D01*
G01X342339Y192225D02*
X341714Y191600D01*
X340732D01*
X340300Y192032D01*
Y198500D01*
X334500Y204300D01*
Y206432D01*
X328500Y212432D01*
Y215232D01*
X322582Y221150D01*
X321089D01*
X320839Y221400D01*
X320300D01*
G01X345500Y190500D02*
X344053Y191947D01*
Y198326D01*
X342150Y200229D01*
Y201050D01*
X334500Y208700D01*
Y211820D01*
X334110Y212210D01*
Y213410D01*
X334500Y213800D01*
Y215199D01*
X334498D01*
X332251Y217446D01*
X331403Y218295D01*
X330851D01*
X330003Y219143D01*
Y219695D01*
X326640Y223059D01*
X326287D01*
G01X342342Y190024D02*
X341566Y190800D01*
X340400D01*
X339500Y191700D01*
Y198168D01*
X338651Y199017D01*
X338100D01*
X337251Y199865D01*
Y200417D01*
X333700Y203968D01*
Y206100D01*
X332851Y206949D01*
X332300D01*
X331451Y207797D01*
Y208349D01*
X330603Y209197D01*
X330051D01*
X329203Y210046D01*
Y210597D01*
X327700Y212100D01*
Y214900D01*
X326851Y215749D01*
X326300D01*
X325451Y216597D01*
Y217149D01*
X324603Y217997D01*
X324051D01*
X323203Y218846D01*
Y219397D01*
X322250Y220350D01*
X321089D01*
X320839Y220100D01*
X320300D01*
G01X337800Y192200D02*
Y191602D01*
X337198Y191000D01*
X336632D01*
X336246Y191386D01*
Y193354D01*
X333900Y195700D01*
Y201532D01*
X331450Y203982D01*
Y205982D01*
X324000Y213432D01*
Y215032D01*
X320432Y218600D01*
X315400D01*
X314139Y217339D01*
X313786D01*
G01X337800Y189200D02*
X336800Y190200D01*
X336300D01*
X335446Y191054D01*
Y193022D01*
X333100Y195368D01*
Y201200D01*
X330650Y203650D01*
Y205650D01*
X327697Y208603D01*
X327146D01*
X326297Y209451D01*
Y210003D01*
X325449Y210851D01*
X324897D01*
X324049Y211700D01*
Y212251D01*
X323200Y213100D01*
Y214700D01*
X322351Y215549D01*
X321800D01*
X320951Y216397D01*
Y216949D01*
X320100Y217800D01*
X318900D01*
X318510Y217410D01*
X317310D01*
X316920Y217800D01*
X315732D01*
X314777Y216845D01*
Y216491D01*
X314706Y216420D01*
G01X333996Y192063D02*
Y192062D01*
X333066Y191132D01*
X332500D01*
X331932Y191700D01*
Y192336D01*
X332300Y192704D01*
Y199943D01*
X329796Y202447D01*
Y204805D01*
X328119Y206482D01*
X325850D01*
X324468Y205100D01*
X308100D01*
X307100Y206100D01*
X305750D01*
X305500Y206350D01*
G01X329972Y196400D02*
X329733D01*
X327764Y198369D01*
X326931D01*
X324432Y200868D01*
X316400D01*
X316150Y201118D01*
X316100D01*
G01X334707Y189383D02*
X333758Y190332D01*
X332168D01*
X331132Y191368D01*
Y192668D01*
X331500Y193036D01*
Y199611D01*
X328996Y202115D01*
Y204473D01*
X327787Y205682D01*
X326182D01*
X324800Y204300D01*
X323800D01*
X323410Y203910D01*
X322210D01*
X321820Y204300D01*
X320620D01*
X320230Y203910D01*
X319030D01*
X318640Y204300D01*
X314228D01*
X313838Y203910D01*
X312638D01*
X312248Y204300D01*
X311048D01*
X310658Y203910D01*
X309458D01*
X309068Y204300D01*
X307768D01*
X306768Y205300D01*
X305750D01*
X305500Y205050D01*
G01X329972Y193559D02*
X328522Y195009D01*
Y196479D01*
X327432Y197569D01*
X326599D01*
X324100Y200068D01*
X319580D01*
X319190Y199678D01*
X317990D01*
X317600Y200068D01*
X316400D01*
X316150Y199818D01*
X316100D01*
G01X326550Y191600D02*
X324550Y193600D01*
X323142D01*
X319222Y197520D01*
X316100D01*
X315850Y197270D01*
X315800D01*
G01X326850Y193900D02*
X326566Y193616D01*
X325666D01*
X324882Y194400D01*
X323474D01*
X319554Y198320D01*
X316100D01*
X315850Y198570D01*
X315800D01*
G01X353342Y186124D02*
X352176Y184958D01*
X348958D01*
X345800Y181800D01*
X341200D01*
X339498Y183502D01*
X329670D01*
X324268Y178100D01*
X322650D01*
X322400Y178350D01*
X322300D01*
G01X353302Y182993D02*
X352137Y184158D01*
X349290D01*
X348381Y183249D01*
Y182697D01*
X347532Y181849D01*
X346981D01*
X346132Y181000D01*
X344048D01*
X343658Y180610D01*
X342458D01*
X342068Y181000D01*
X340868D01*
X339166Y182702D01*
X330002D01*
X324600Y177300D01*
X322650D01*
X322400Y177050D01*
X322300D01*
G01X402050Y102064D02*
X389914Y114200D01*
Y124536D01*
G01X396700Y128000D02*
Y127800D01*
X395050Y126150D01*
G02X393315Y125608I-1735J2506D01*
G03X392200Y125300I886J-5381D01*
G03X391675Y124684I315J-800D01*
G01X391403Y122900D01*
Y114497D01*
X403296Y102604D01*
X403803D01*
G01X405537Y108187D02*
X403202Y110522D01*
X400978D01*
X398250Y113250D01*
G03X397180Y113887I-1372J-1088D01*
G02X396197Y114498I0J1096D01*
G01X395347Y115348D01*
G02X394800Y117000I2221J1652D01*
G01Y119100D01*
X394228Y119672D01*
X393052D01*
X392203Y120521D01*
Y122703D01*
X393482Y123982D01*
G01X407865Y208435D02*
X397970Y198540D01*
X397520D01*
X395050Y196070D01*
G03X394430Y194573I1497J-1497D01*
G01Y192016D01*
G02X394150Y191340I-956J0D01*
G01Y188483D01*
X394092Y188425D01*
Y187208D01*
X395420Y185880D01*
X395981D01*
X398895Y182966D01*
X400252D01*
G01X397805Y192061D02*
Y192115D01*
X397710Y192210D01*
Y195910D01*
X400500Y198700D01*
X407100D01*
X410600Y202200D01*
Y209600D01*
X413800Y212800D01*
Y221300D01*
G01X417800Y217400D02*
Y214500D01*
X412450Y209150D01*
Y201050D01*
X406500Y195100D01*
X405200D01*
X403500Y196800D01*
X401200D01*
X400301Y195901D01*
Y186099D01*
G01X432628Y96538D02*
Y97369D01*
X430900Y99097D01*
Y106921D01*
X429857Y107964D01*
X428243D01*
X427853Y107574D01*
X426653D01*
X426263Y107964D01*
X421864D01*
X421863Y107963D01*
X421201D01*
X419595Y109569D01*
X419043D01*
X418195Y110418D01*
Y110969D01*
X417346Y111818D01*
Y114396D01*
X420260Y117310D01*
X420600Y118071D01*
Y118300D01*
G01X436300Y137800D02*
X435500D01*
X433000Y135300D01*
X431800D01*
X430300Y136800D01*
X424200D01*
X422100Y134700D01*
X417283D01*
X416000Y135983D01*
G01X413300Y139100D02*
X413500Y138900D01*
Y136000D01*
X415600Y133900D01*
X430932D01*
X431532Y133300D01*
X436494D01*
G01X436900Y131700D02*
X435550Y130350D01*
X433350D01*
X430700Y133000D01*
X412300D01*
X410400Y134900D01*
Y139600D01*
X413400Y142600D01*
Y142700D01*
G01X418000Y142500D02*
X419217Y145690D01*
X419400Y146300D01*
X419351Y147985D01*
X419330Y150290D01*
X419540Y150920D01*
X421470Y151960D01*
X422416Y152168D01*
X429229Y152267D01*
X433017Y152855D01*
X433919Y153185D01*
X438694Y155906D01*
X439388Y156600D01*
G01X415992Y186205D02*
X419315D01*
X421110Y188000D01*
X422449D01*
X422459Y187990D01*
X426313D01*
X426473Y188150D01*
X446650D01*
X449300Y190800D01*
X459000D01*
G01X415992Y189254D02*
X414586Y187269D01*
X414300Y186600D01*
Y185900D01*
X414530Y185130D01*
X414730Y184930D01*
X415500Y184669D01*
X418300D01*
X435100Y183700D01*
X456400D01*
G01X419097Y189563D02*
X417589Y191070D01*
Y192608D01*
X416740Y193457D01*
X416263D01*
X414860Y194860D01*
Y196300D01*
X416650Y198090D01*
X417007D01*
X418700Y199783D01*
Y206897D01*
X424901Y213098D01*
Y215401D01*
G01X416500Y195563D02*
X417350Y196413D01*
Y197301D01*
X419500Y199451D01*
Y206565D01*
X424709Y211774D01*
X425109D01*
X427100Y213765D01*
Y213800D01*
G01X416900Y200100D02*
X415803D01*
X414903Y201000D01*
Y202500D01*
X416000Y203597D01*
Y204600D01*
X414700Y205900D01*
Y209000D01*
X415700Y210000D01*
X417000D01*
X418100Y211100D01*
Y212100D01*
X421600Y215600D01*
Y226900D01*
X423100Y228400D01*
G01X429105Y106337D02*
X429490Y105952D01*
Y97064D01*
X432000Y94554D01*
Y92800D01*
X433424Y91376D01*
X433676D01*
G01X432509Y90209D02*
Y91159D01*
X431200Y92468D01*
Y94222D01*
X428690Y96732D01*
Y104480D01*
X428400Y104770D01*
X427560D01*
G01X433700Y97800D02*
X433329D01*
X431700Y99429D01*
Y107253D01*
X430189Y108764D01*
X421532D01*
X418146Y112150D01*
Y114064D01*
X420782Y116700D01*
G03X421900Y117200I0J1500D01*
G01X422100Y117400D01*
G03X422300Y118300I-1925J900D01*
G03X421886Y119386I-1631J0D01*
G01X420672Y120600D01*
G01X436575Y100100D02*
X437034Y100559D01*
Y100934D01*
X433096Y104872D01*
Y107572D01*
X430868Y109800D01*
X425468D01*
X422801Y112467D01*
Y114407D01*
X422042Y115224D01*
G01X440575Y101319D02*
X440539Y101355D01*
Y101878D01*
X436396Y106021D01*
Y108283D01*
X430824Y113855D01*
X429905D01*
X429230Y114530D01*
X428130D01*
X427900Y114300D01*
G01X428100Y116500D02*
X428392D01*
X430237Y114655D01*
X431156D01*
X437196Y108615D01*
Y106353D01*
X441063Y102486D01*
X441742D01*
G01X424700Y115000D02*
X423601Y113901D01*
Y112799D01*
X425800Y110600D01*
X431200D01*
X433896Y107904D01*
Y105204D01*
X437834Y101266D01*
Y100491D01*
X438225Y100100D01*
G01X425000Y135350D02*
X430614D01*
X431632Y134332D01*
X433532D01*
X434500Y135300D01*
X436000D01*
G01X430400Y150000D02*
X426700D01*
X422300Y145600D01*
X420000Y143500D01*
X419862Y142516D01*
X419880Y141485D01*
X420100Y141100D01*
X422400Y139000D01*
G01X437103Y139503D02*
X434503D01*
X433348Y138348D01*
X431448D01*
X430700Y137600D01*
X423400D01*
X422200Y136400D01*
X419500D01*
G01X437900Y148112D02*
X430992D01*
X427825Y145974D01*
X427501Y145650D01*
X426541Y144875D01*
X424856Y142270D01*
G01X436644Y143500D02*
X436544Y143600D01*
X434132D01*
X433400Y142868D01*
Y140468D01*
X432432Y139500D01*
X430584D01*
X430084Y140000D01*
X429331D01*
X428390Y139059D01*
G01X437300Y144400D02*
X433800D01*
X432600Y143200D01*
Y140800D01*
X432100Y140300D01*
X430916D01*
X430500Y140716D01*
Y142081D01*
X430694Y142275D01*
G01X429000Y210000D02*
X426800Y207800D01*
X424500D01*
X423261Y206561D01*
Y201461D01*
X422900Y201100D01*
Y198225D01*
X421171Y196496D01*
G01X463600Y193025D02*
X461425Y195200D01*
X451200D01*
X444950Y188950D01*
X429846D01*
X429100Y189696D01*
G01X463100Y200000D02*
X460700Y202400D01*
X435200D01*
X432000Y199200D01*
Y196400D01*
X426384Y190784D01*
X426173D01*
G01X463725Y201675D02*
X461600Y203800D01*
X434300D01*
X428308Y197808D01*
Y195901D01*
X428830Y195379D01*
G01X422152Y189600D02*
Y191157D01*
X427082Y196087D01*
Y198407D01*
X434175Y205500D01*
X441400D01*
X441550Y205350D01*
G01X462950Y180100D02*
X462250Y180800D01*
X437700D01*
X435676Y182824D01*
X418624D01*
X418600Y182800D01*
G01X432100Y190400D02*
X432750Y191050D01*
X438600D01*
X440700Y193150D01*
Y196000D01*
X443500Y198800D01*
X461100D01*
X464425Y195475D01*
G01X438800Y208300D02*
X432400D01*
X429949Y205849D01*
X425710D01*
X424861Y205000D01*
Y202939D01*
X426700Y201100D01*
Y199418D01*
X425500Y198218D01*
Y196100D01*
X423100Y193700D01*
X421400D01*
X420800Y193100D01*
G01X461000Y187200D02*
X460867Y187067D01*
X447265D01*
X446982Y187350D01*
X426805D01*
X425500Y186045D01*
G01X429300Y224500D02*
Y224000D01*
X428700Y223400D01*
X425900D01*
X425300Y224000D01*
Y225900D01*
X424700Y226500D01*
X423756D01*
X423156Y225900D01*
Y221286D01*
X423756Y220686D01*
X424700D01*
X425300Y220086D01*
Y217900D01*
X424700Y217300D01*
X424100D01*
X423500Y216700D01*
Y213825D01*
X420975Y211300D01*
G01X427900Y202800D02*
X428800D01*
X432800Y206800D01*
X440400D01*
G01X434175Y212175D02*
X428900Y206900D01*
X425200D01*
X424061Y205761D01*
Y200945D01*
X424832Y200174D01*
G01X428800Y212600D02*
X427174Y210974D01*
X425041D01*
X421811Y207744D01*
Y202603D01*
G01X437800Y128100D02*
X436793D01*
X433700Y125007D01*
Y123000D01*
X434400Y122300D01*
X434900D01*
G03X436405Y122794I0J2540D01*
G01X436711Y123100D01*
G02X437407Y123363I1088J-1827D01*
G02X438200Y123100I0J-1327D01*
G01X439275Y122025D01*
G02X440178Y121913I-2J-3713D01*
G01X440973Y121195D01*
X441110Y120754D01*
X441500Y119500D01*
X443086Y118387D01*
G54D11*
G01X10636Y-27865D02*
G02I-12000J0D01*
G01X14636D02*
X-17364D01*
G01X5486D02*
G02I-6850J0D01*
G01X-1364Y-43865D02*
Y-11865D01*
G01X14636Y-43865D02*
Y-123865D01*
G01D02*
X1309236D01*
G01X14636Y-79365D02*
X1309236D01*
G01X14636Y-43865D02*
X1309236D01*
G01X104000Y115500D02*
Y118757D01*
X90649Y132108D01*
Y161963D01*
X58698Y193914D01*
Y197914D01*
X44861Y211751D01*
Y227261D01*
G01X186300Y172400D02*
Y178078D01*
X172946Y191432D01*
Y195446D01*
X187000Y209500D01*
G01X207200Y106000D02*
X210900D01*
X216125Y111225D01*
Y116796D01*
X223900Y124571D01*
Y135600D01*
X228000Y139700D01*
G01X326100Y267000D02*
X329500D01*
X333200Y263300D01*
X342826D01*
X347026Y267500D01*
X384000D01*
X391800Y259700D01*
X410404D01*
X411604Y258500D01*
X411605D01*
X420400Y249705D01*
Y244400D01*
X420000Y244000D01*
G01X400900Y273000D02*
X399900Y272000D01*
X345100D01*
X343600Y270500D01*
G01X451300Y21700D02*
Y40078D01*
X421114Y70264D01*
X372405D01*
X370841Y68700D01*
X366700D01*
G01X433300Y274100D02*
X425872Y266672D01*
X425672D01*
X417000Y258000D01*
G01X433300Y274100D02*
X435800Y271600D01*
X447300D01*
X449400Y273700D01*
G01D02*
X450500Y272600D01*
Y269000D01*
X453410Y266090D01*
X472101D01*
G01X505315Y268500D02*
X505015Y268800D01*
X474423D01*
X472101Y266478D01*
Y266090D01*
G01X521736Y-43865D02*
Y-123865D01*
G01X659236Y-43865D02*
Y-123865D01*
G01X656200Y144000D02*
X656500D01*
X657000Y144500D01*
X698600D01*
X711200Y131900D01*
X714900D01*
G01X774236Y-43865D02*
Y-123865D01*
G01X941736Y-43865D02*
Y-123865D01*
G01X1111736Y-43865D02*
Y-123865D01*
G01X1309236Y-43865D02*
Y-123865D01*
G01X1341236Y-27865D02*
X1309236D01*
G01X1337236D02*
G02I-12000J0D01*
G01X1332086D02*
G02I-6850J0D01*
G01X1325236Y-43865D02*
Y-11865D01*
X32800Y120400D03*
X29200Y120300D03*
X30000Y196200D03*
X31500Y207500D03*
X40500Y127700D03*
X38500Y148000D03*
X48500D03*
X41000Y152300D03*
Y143300D03*
X46000D03*
Y152300D03*
X43500Y148000D03*
Y138500D03*
X48500D03*
X38500D03*
X45800Y158100D03*
X34800Y198800D03*
Y203700D03*
X37600Y212700D03*
Y207800D03*
X34500Y216000D03*
X40400Y217100D03*
X40700Y224000D03*
X44861Y227261D03*
X40200Y238300D03*
Y231300D03*
Y245300D03*
X44400Y250400D03*
X40500Y260000D03*
X40600Y252500D03*
X52500Y96500D03*
Y106500D03*
X57500Y96500D03*
X60000Y101500D03*
X50000D03*
X55000D03*
X57500Y106500D03*
X60000Y111300D03*
X50000D03*
X55000D03*
X54700Y192200D03*
X52700Y184800D03*
X62800Y184300D03*
X57009Y230009D03*
X57500Y223200D03*
X57800Y253900D03*
X80031Y40357D03*
X76411D03*
X79700Y67500D03*
X79500Y230000D03*
X78700Y259800D03*
X67600Y255800D03*
X66300Y259300D03*
X74000Y271400D03*
X67000Y263200D03*
X92159Y40357D03*
X90600Y63200D03*
X94000Y63300D03*
X92900Y204008D03*
X89500Y204000D03*
X84500Y230000D03*
X89500D03*
X84500Y225000D03*
Y235000D03*
X91400Y270300D03*
X95779Y40357D03*
X107907D03*
X109600Y63700D03*
X96200Y60700D03*
X106100Y158700D03*
X99600Y225700D03*
X99328Y235370D03*
X109000Y231400D03*
X120000Y40700D03*
X123655Y40357D03*
X111527D03*
X120700Y135500D03*
X119600Y143300D03*
X125000Y178000D03*
X119760Y191419D03*
X115760D03*
X123760D03*
X136600Y44800D03*
X139403Y40357D03*
X127275D03*
X138574Y57924D03*
X130000Y121000D03*
X133975Y129141D03*
X127500Y129180D03*
X135412Y141400D03*
X138600Y146300D03*
X137300Y158900D03*
X140000Y195500D03*
X137100Y188900D03*
X143023Y40357D03*
X155151D03*
X147400Y60400D03*
X142900Y138595D03*
X150500Y183000D03*
X157000Y169194D03*
X158771Y40357D03*
X170899D03*
X157500Y149025D03*
X161900Y161700D03*
X165900Y181500D03*
X163700Y178900D03*
X169800Y181448D03*
X165700Y203400D03*
X162000Y226000D03*
X167000D03*
Y221500D03*
X162000D03*
Y230500D03*
X167000D03*
X162000Y235000D03*
X174519Y40357D03*
X186647D03*
X183726Y106353D03*
X187500Y106500D03*
X175787Y127000D03*
X176700Y144875D03*
X176400Y175700D03*
X186300Y172400D03*
X177500Y209500D03*
X187000D03*
X176800Y241600D03*
X190267Y40357D03*
X199441Y187547D03*
X199392Y190947D03*
X202761Y186811D03*
X207200Y106000D03*
X207861Y188540D03*
X215384Y202984D03*
X205920Y221550D03*
X229300Y42950D03*
X221400Y64500D03*
X226500Y94450D03*
X227800Y101200D03*
X228000Y139700D03*
X232921Y167505D03*
X244400Y50600D03*
X235400Y63400D03*
X241200Y94900D03*
X235075Y105600D03*
X254600Y41100D03*
X265140Y40490D03*
X253700Y75875D03*
X250300Y73800D03*
X257977Y163423D03*
X253500Y174360D03*
X268910Y40490D03*
X268900Y129386D03*
X272300Y149900D03*
X278300Y173300D03*
X276910Y189400D03*
X273060Y189374D03*
X284758Y40490D03*
X280988D03*
X282460Y189400D03*
X286300Y191885D03*
X291201Y225025D03*
X287802Y225200D03*
X287400Y254100D03*
X287250Y269250D03*
X296736Y40490D03*
X300506D03*
X299800Y82300D03*
X300700Y142850D03*
X307231Y164059D03*
X302600Y253600D03*
X321900Y44000D03*
X312484Y40690D03*
X316254D03*
X311950Y50800D03*
X324000Y54900D03*
X326000Y254100D03*
X326100Y267000D03*
X327577Y48475D03*
X327400Y54900D03*
X366700Y68700D03*
X388000Y72963D03*
X394229Y241128D03*
X391788Y238760D03*
X399438Y243839D03*
X401838Y246248D03*
X400900Y273000D03*
X417000Y258000D03*
X426405Y25054D03*
X427000Y17000D03*
X423500Y16885D03*
X430000Y34158D03*
X420000Y244000D03*
X423900Y257500D03*
X433300Y274100D03*
X442100Y7006D03*
X437061Y10393D03*
X434900Y6925D03*
X446800Y9900D03*
X438300Y6925D03*
X449600Y5900D03*
X446200D03*
X436240Y26300D03*
X436106Y34506D03*
X435700Y243250D03*
X449400Y273700D03*
X451300Y21700D03*
X451000Y257413D03*
X456300Y275300D03*
X467700Y245500D03*
X472101Y266090D03*
X511500Y119500D03*
X505315Y268500D03*
X528100Y119500D03*
X607500Y188300D03*
X631900Y175850D03*
X634748Y177708D03*
X633100Y198300D03*
X629700D03*
X640461Y181410D03*
X646000Y186400D03*
X636500Y198300D03*
X656200Y144000D03*
X657722Y193800D03*
X654851Y191978D03*
X673100Y179455D03*
X676200Y181600D03*
X673044Y190456D03*
X668732Y204555D03*
X684700Y179800D03*
X698970Y118149D03*
X699241Y114759D03*
X698000Y181500D03*
X704700Y183800D03*
X714900Y131900D03*
X717000Y187500D03*
X715500Y205837D03*
X739500Y114900D03*
X741104Y133763D03*
X736900Y162300D03*
X729500D03*
X733400D03*
X737000Y188315D03*
X739900Y212800D03*
X734000Y205000D03*
X739800Y216300D03*
X756000Y106000D03*
X758176Y135024D03*
X745104Y129763D03*
X749104Y133763D03*
X745104D03*
X752191Y146613D03*
X745104Y137763D03*
X747000Y162000D03*
X750500D03*
X746000Y182300D03*
X743000Y211000D03*
X744100Y221900D03*
X743800Y215900D03*
X768500Y114000D03*
X774500Y31307D03*
X778000D03*
X779000Y142000D03*
X788515Y144060D03*
X784515D03*
X796515D03*
X792515D03*
X800515D03*
Y148060D03*
X796515D03*
X792515D03*
G54D21*
G01X399438Y243839D02*
X399434Y245537D01*
X398471Y246500D01*
X361805D01*
X360380Y247925D01*
X271857D01*
X269232Y245300D01*
X263700D01*
X249850Y231450D01*
X239308D01*
X224108Y216250D01*
X100450D01*
X91700Y207500D01*
Y205307D01*
X92800Y204207D01*
Y204108D01*
X92900Y204008D01*
G01X401838Y246248D02*
X400139D01*
X398886Y247500D01*
X362220D01*
X360795Y248925D01*
X271442D01*
X268817Y246300D01*
X263285D01*
X249435Y232450D01*
X238893D01*
X223693Y217250D01*
X100035D01*
X90700Y207915D01*
Y205200D01*
X89500Y204000D01*
G01X257977Y163423D02*
Y164321D01*
X261800Y168144D01*
Y172917D01*
X263833Y174950D01*
X265367D01*
X265434Y174883D01*
X267568D01*
X282059Y189374D01*
X282434D01*
X282460Y189400D01*
G01X442100Y7006D02*
Y10599D01*
X433400Y19299D01*
Y48924D01*
X418460Y63864D01*
X375059D01*
X373495Y62300D01*
X340091D01*
X335638Y66753D01*
Y68012D01*
X310500Y93150D01*
Y99500D01*
X307577Y102423D01*
Y111077D01*
X304400Y114254D01*
Y122200D01*
X311000Y128800D01*
Y135600D01*
X309000Y137600D01*
G54D12*
X303610Y110800D03*
X304149Y128349D03*
X307854Y130539D03*
X309000Y137600D03*
Y158806D03*
X303480Y189100D03*
X301300Y188700D03*
X309700Y187997D03*
X307500Y188000D03*
X317641Y90956D03*
X318900Y98000D03*
X317600Y93625D03*
X316844Y196010D03*
X319801Y194890D03*
X326550Y191600D03*
X329300Y87300D03*
X331200Y88600D03*
X330900Y93400D03*
X335514Y138220D03*
X338320Y141300D03*
X335499Y153846D03*
X336900Y161600D03*
X336800Y164434D03*
X339300Y174100D03*
X337800Y189200D03*
X326850Y193900D03*
X329972Y196400D03*
Y193559D03*
X333996Y192063D03*
X334707Y189383D03*
X337800Y192200D03*
X351500Y136000D03*
X357300Y128600D03*
X355400Y137100D03*
X354300Y128600D03*
X346944Y156775D03*
X350700Y155600D03*
X345900Y161700D03*
X353302Y182993D03*
X356900Y186100D03*
X349600Y194800D03*
X342339Y192225D03*
X342342Y190024D03*
X349100Y191900D03*
X353625Y195045D03*
Y192045D03*
X356600Y195700D03*
X356700Y193300D03*
X345503Y193474D03*
X345500Y190500D03*
X349100Y189700D03*
X353342Y186124D03*
X362111Y127142D03*
X362120Y124153D03*
X359421Y127128D03*
Y124008D03*
X359300Y130000D03*
X367900Y152550D03*
X368026Y149718D03*
X368100Y165300D03*
X364600D03*
X367950Y159200D03*
X371157Y162320D03*
X371176Y158940D03*
X358477Y159300D03*
X386853Y149640D03*
X386800Y165300D03*
X380398Y165240D03*
X383781Y165235D03*
X396276Y120948D03*
X393482Y123982D03*
X396700Y128000D03*
X389914Y124536D03*
X392998Y133968D03*
X396148D03*
X396321Y136987D03*
X402561Y137000D03*
X399298Y137118D03*
X392998D03*
X389848D03*
X402400Y140163D03*
X396148Y140268D03*
X399298D03*
X392998Y165240D03*
X400252Y182966D03*
X400301Y186099D03*
X397805Y192061D03*
X392700Y193563D03*
X416000Y135983D03*
X413300Y139100D03*
X413400Y142700D03*
X418000Y142500D03*
X418600Y182800D03*
X415992Y189254D03*
Y186205D03*
X419097Y189563D03*
X416500Y195563D03*
X416900Y200100D03*
X427560Y104770D03*
X429105Y106337D03*
X420600Y118300D03*
X420672Y120600D03*
X422042Y115224D03*
X424700Y115000D03*
X427900Y114300D03*
X428100Y116500D03*
X428255Y126236D03*
X425000Y135350D03*
X419500Y136400D03*
X424856Y142270D03*
X422400Y139000D03*
X430694Y142275D03*
X428390Y139059D03*
X432100Y190400D03*
X429100Y189696D03*
X426173Y190784D03*
X428830Y195379D03*
X422152Y189600D03*
X420800Y193100D03*
X421171Y196496D03*
X425500Y186045D03*
X420975Y211300D03*
X427900Y202800D03*
X424832Y200174D03*
X421811Y202603D03*
X437400Y121600D03*
X442842Y120824D03*
X438500Y116400D03*
X439400Y120100D03*
X444242Y124324D03*
X435442Y124024D03*
X437800Y128100D03*
X506800Y12907D03*
X508700Y17207D03*
X506500Y32807D03*
X507817Y252248D03*
X511200Y258900D03*
X509244Y272796D03*
X514360Y12417D03*
X526000Y12507D03*
X519426Y12318D03*
X522311Y16720D03*
X514300Y20507D03*
X519623Y20457D03*
X522700Y30007D03*
X513005Y32412D03*
X519400Y33340D03*
X526700Y33207D03*
X516600Y252200D03*
X521800Y252875D03*
X513776Y258563D03*
X516727Y273122D03*
X521790Y273140D03*
X517100Y265100D03*
X521987D03*
X537964Y12317D03*
X532500Y13407D03*
X541114Y12307D03*
X528219Y15096D03*
X532472Y20515D03*
X537410Y20584D03*
X529000Y30007D03*
X541950Y33340D03*
X532542Y33307D03*
X537200Y33207D03*
X532900Y255300D03*
X535098Y252600D03*
X540900Y252300D03*
X527400Y252100D03*
X529300Y271000D03*
X528330Y273140D03*
X539937Y272989D03*
X539505Y265100D03*
X534905Y273097D03*
X534700Y265100D03*
X547500Y12507D03*
X553720Y12297D03*
X550234Y14997D03*
X553797Y20496D03*
X549500Y29107D03*
X553250Y33207D03*
X547306Y33134D03*
X552800Y255300D03*
X545500Y252600D03*
X553485Y252332D03*
X546200Y271000D03*
X554500Y264900D03*
X546900Y273100D03*
X554434Y272914D03*
X558448Y12407D03*
X566040Y12317D03*
X566000Y16507D03*
X572200Y28707D03*
X558500Y20507D03*
X573200Y19907D03*
X565470Y33287D03*
X573242Y32462D03*
X560635Y33264D03*
X560555Y252503D03*
X563376Y256627D03*
X566151Y252115D03*
X572150Y252200D03*
X570200Y269700D03*
X559600Y272900D03*
X572155Y264900D03*
X565700Y273050D03*
X559700Y264900D03*
X572700Y273100D03*
X573470Y12347D03*
X578620Y12357D03*
X585280Y12267D03*
X583700Y28207D03*
X578600Y20307D03*
X579100Y33207D03*
X585550Y33340D03*
X582300Y254900D03*
X578800Y252200D03*
X577450Y264900D03*
X580107Y270501D03*
X577636Y272947D03*
X590000Y14007D03*
X594500Y4007D03*
X600896Y12407D03*
X601000Y20507D03*
X590500Y30507D03*
X594200Y33607D03*
X600360Y33287D03*
X594600Y260000D03*
X590837Y259889D03*
X598398Y260199D03*
X594500Y265200D03*
X590700Y264833D03*
X598300Y265400D03*
X602450Y272900D03*
X595386Y272932D03*
X616600Y12307D03*
X605700Y12407D03*
X616707Y15616D03*
X610800Y14807D03*
X605728Y20518D03*
X618900Y33290D03*
X615103Y30690D03*
X610500Y30507D03*
X607544Y33340D03*
X619382Y260089D03*
X615532Y259700D03*
X611706Y259387D03*
X615537Y264789D03*
X619100Y265300D03*
X611536Y264385D03*
X606200Y267800D03*
X612393Y273026D03*
X633500Y12406D03*
X624000D03*
X634757Y22707D03*
X623480Y22564D03*
X631007Y22707D03*
X627257Y22407D03*
X624100Y33190D03*
X633449D03*
X630432Y260100D03*
X626682Y260300D03*
X622933Y260189D03*
X634207Y260300D03*
X630455Y265400D03*
X634280Y265332D03*
X626651Y265489D03*
X622899Y265189D03*
X629937Y272990D03*
X620437D03*
X644193Y12907D03*
X648800Y12707D03*
X641745Y12367D03*
X645300Y15507D03*
X648400Y15490D03*
X642257Y23307D03*
X638507Y23183D03*
X647000Y29607D03*
X649550Y30807D03*
X643700Y33290D03*
X644100Y30307D03*
X641900Y31507D03*
X638032Y260342D03*
X638090Y265340D03*
X639500Y268800D03*
X662359Y12379D03*
X662192Y14874D03*
X662503Y33207D03*
X657900Y30690D03*
X664678Y30307D03*
X661708Y30699D03*
X665901Y12307D03*
X666175Y14807D03*
X709000Y12407D03*
X708900Y30407D03*
X723586Y14080D03*
X712182Y14124D03*
X720100Y14707D03*
X718375Y22907D03*
X715090D03*
X723500Y29907D03*
X721747Y32954D03*
X712400Y30807D03*
G54D22*
G01X70851Y-113865D02*
Y-96365D01*
G01X80021D02*
Y-113865D01*
G01Y-105115D02*
X70851D01*
G01X92936Y-113865D02*
X91626Y-113573D01*
X90316Y-112407D01*
X89442Y-110365D01*
X89006Y-108032D01*
X89442Y-105698D01*
X90316Y-103657D01*
X91626Y-102490D01*
X92936Y-102199D01*
X94246Y-102490D01*
X95556Y-103657D01*
X96429Y-105698D01*
X96648Y-108032D01*
X96429Y-110365D01*
X95556Y-112407D01*
X94246Y-113573D01*
X92936Y-113865D01*
G01X106724D02*
Y-102199D01*
G01Y-105115D02*
X107598Y-103657D01*
X108908Y-102490D01*
X110654Y-102199D01*
X112182Y-102490D01*
X113493Y-103657D01*
X114148Y-105698D01*
Y-113865D01*
G01X124661Y-105990D02*
X131648D01*
X130993Y-103948D01*
X129901Y-102782D01*
X128373Y-102199D01*
X126844Y-102490D01*
X125534Y-103365D01*
X124661Y-105407D01*
X124224Y-107157D01*
Y-108907D01*
X124661Y-110657D01*
X125753Y-112407D01*
X127063Y-113573D01*
X128591Y-113865D01*
X130119Y-113282D01*
X131648Y-111532D01*
G01X140851Y-119115D02*
X142161Y-119698D01*
X143908Y-119115D01*
X144999Y-117949D01*
X145873Y-116490D01*
X147182Y-111824D01*
X150021Y-102199D01*
G01X143034D02*
X147182Y-111824D01*
G01X182182Y-104532D02*
X183056Y-103657D01*
X183711Y-102199D01*
X184148Y-100156D01*
X183711Y-98407D01*
X182838Y-97240D01*
X181309Y-96365D01*
X175414D01*
Y-113865D01*
X182619D01*
X184148Y-112699D01*
X185021Y-110948D01*
X185458Y-108907D01*
X185021Y-106865D01*
X183711Y-105115D01*
X182182Y-104532D01*
X175414D01*
G01X201866Y-113865D02*
Y-102199D01*
G01Y-104240D02*
X200993Y-103074D01*
X199682Y-102490D01*
X198154Y-102199D01*
X196626Y-102782D01*
X195316Y-103948D01*
X194442Y-105698D01*
X194006Y-108032D01*
X194442Y-110365D01*
X195316Y-112115D01*
X196626Y-113282D01*
X198154Y-113865D01*
X199682Y-113573D01*
X200993Y-112699D01*
X201866Y-111532D01*
G01X219366Y-96365D02*
Y-113865D01*
G01Y-111241D02*
X218493Y-112699D01*
X217182Y-113573D01*
X215654Y-113865D01*
X213908Y-113282D01*
X212598Y-111824D01*
X211724Y-110074D01*
X211506Y-108032D01*
X211724Y-105990D01*
X212598Y-104240D01*
X213908Y-102782D01*
X215654Y-102199D01*
X217182Y-102490D01*
X218274Y-103074D01*
X219366Y-104240D01*
G01X229879Y-118240D02*
X231408Y-119407D01*
X233154Y-119698D01*
X234682Y-119407D01*
X235993Y-117949D01*
X236866Y-115907D01*
Y-102199D01*
G01Y-104532D02*
X235993Y-103365D01*
X234682Y-102490D01*
X233154Y-102199D01*
X231408Y-102782D01*
X230316Y-103948D01*
X229442Y-105990D01*
X229006Y-108032D01*
X229224Y-109782D01*
X230098Y-111824D01*
X231408Y-113282D01*
X233154Y-113865D01*
X234464Y-113573D01*
X235993Y-112407D01*
X236866Y-111241D01*
G01X247161Y-105990D02*
X254148D01*
X253493Y-103948D01*
X252401Y-102782D01*
X250873Y-102199D01*
X249344Y-102490D01*
X248034Y-103365D01*
X247161Y-105407D01*
X246724Y-107157D01*
Y-108907D01*
X247161Y-110657D01*
X248253Y-112407D01*
X249563Y-113573D01*
X251091Y-113865D01*
X252619Y-113282D01*
X254148Y-111532D01*
G01X264879Y-113865D02*
Y-102199D01*
G01Y-104532D02*
X265971Y-103365D01*
X267063Y-102490D01*
X268591Y-102199D01*
X269682Y-102490D01*
X270993Y-103365D01*
G01X298569Y-113865D02*
Y-96365D01*
X303809D01*
X305556Y-97240D01*
X306866Y-99282D01*
X307303Y-101615D01*
X306866Y-103948D01*
X305774Y-105698D01*
X303809Y-106574D01*
X298569D01*
G01X324366Y-113865D02*
Y-102199D01*
G01Y-104240D02*
X323493Y-103074D01*
X322182Y-102490D01*
X320654Y-102199D01*
X319126Y-102782D01*
X317816Y-103948D01*
X316942Y-105698D01*
X316506Y-108032D01*
X316942Y-110365D01*
X317816Y-112115D01*
X319126Y-113282D01*
X320654Y-113865D01*
X322182Y-113573D01*
X323493Y-112699D01*
X324366Y-111532D01*
G01X334224Y-113865D02*
Y-102199D01*
G01Y-105115D02*
X335098Y-103657D01*
X336408Y-102490D01*
X338154Y-102199D01*
X339682Y-102490D01*
X340993Y-103657D01*
X341648Y-105698D01*
Y-113865D01*
G01X355436Y-96365D02*
Y-113865D01*
G01X352379Y-102199D02*
X358493D01*
G01X369224Y-113865D02*
Y-96365D01*
G01Y-104823D02*
X370316Y-103365D01*
X371408Y-102490D01*
X373154Y-102199D01*
X374464Y-102490D01*
X375993Y-103657D01*
X376648Y-105407D01*
Y-113865D01*
G01X387161Y-105990D02*
X394148D01*
X393493Y-103948D01*
X392401Y-102782D01*
X390873Y-102199D01*
X389344Y-102490D01*
X388034Y-103365D01*
X387161Y-105407D01*
X386724Y-107157D01*
Y-108907D01*
X387161Y-110657D01*
X388253Y-112407D01*
X389563Y-113573D01*
X391091Y-113865D01*
X392619Y-113282D01*
X394148Y-111532D01*
G01X404879Y-113865D02*
Y-102199D01*
G01Y-104532D02*
X405971Y-103365D01*
X407063Y-102490D01*
X408591Y-102199D01*
X409682Y-102490D01*
X410993Y-103365D01*
G01X437259Y-113865D02*
Y-96365D01*
X442936Y-110948D01*
X448613Y-96365D01*
Y-113865D01*
G01X462182Y-104532D02*
X463056Y-103657D01*
X463711Y-102199D01*
X464148Y-100156D01*
X463711Y-98407D01*
X462838Y-97240D01*
X461309Y-96365D01*
X455414D01*
Y-113865D01*
X462619D01*
X464148Y-112699D01*
X465021Y-110948D01*
X465458Y-108907D01*
X465021Y-106865D01*
X463711Y-105115D01*
X462182Y-104532D01*
X455414D01*
G01X227259Y-68865D02*
Y-51365D01*
X232936Y-65948D01*
X238613Y-51365D01*
Y-68865D01*
G01X250436D02*
X249126Y-68573D01*
X247816Y-67407D01*
X246942Y-65365D01*
X246506Y-63032D01*
X246942Y-60698D01*
X247816Y-58657D01*
X249126Y-57490D01*
X250436Y-57199D01*
X251746Y-57490D01*
X253056Y-58657D01*
X253929Y-60698D01*
X254148Y-63032D01*
X253929Y-65365D01*
X253056Y-67407D01*
X251746Y-68573D01*
X250436Y-68865D01*
G01X271866Y-51365D02*
Y-68865D01*
G01Y-66241D02*
X270993Y-67699D01*
X269682Y-68573D01*
X268154Y-68865D01*
X266408Y-68282D01*
X265098Y-66824D01*
X264224Y-65074D01*
X264006Y-63032D01*
X264224Y-60990D01*
X265098Y-59240D01*
X266408Y-57782D01*
X268154Y-57199D01*
X269682Y-57490D01*
X270774Y-58074D01*
X271866Y-59240D01*
G01X282161Y-60990D02*
X289148D01*
X288493Y-58948D01*
X287401Y-57782D01*
X285873Y-57199D01*
X284344Y-57490D01*
X283034Y-58365D01*
X282161Y-60407D01*
X281724Y-62157D01*
Y-63907D01*
X282161Y-65657D01*
X283253Y-67407D01*
X284563Y-68573D01*
X286091Y-68865D01*
X287619Y-68282D01*
X289148Y-66532D01*
G01X302936Y-68865D02*
Y-51365D01*
G01X542319Y-68865D02*
Y-51365D01*
X547559D01*
X549306Y-52240D01*
X550616Y-54282D01*
X551053Y-56615D01*
X550616Y-58948D01*
X549524Y-60698D01*
X547559Y-61574D01*
X542319D01*
G01X568989Y-52824D02*
X567679Y-51948D01*
X566151Y-51365D01*
X564404D01*
X562439Y-52240D01*
X560911Y-53698D01*
X559819Y-55449D01*
X558946Y-58365D01*
X558727Y-60990D01*
X559164Y-63615D01*
X559819Y-65365D01*
X561129Y-67115D01*
X562658Y-68282D01*
X564186Y-68865D01*
X565714D01*
X567243Y-68282D01*
X568553Y-67407D01*
X569645Y-66241D01*
G01X583432Y-59532D02*
X584306Y-58657D01*
X584961Y-57199D01*
X585398Y-55156D01*
X584961Y-53407D01*
X584088Y-52240D01*
X582559Y-51365D01*
X576664D01*
Y-68865D01*
X583869D01*
X585398Y-67699D01*
X586271Y-65948D01*
X586708Y-63907D01*
X586271Y-61865D01*
X584961Y-60115D01*
X583432Y-59532D01*
X576664D01*
G01X592636Y-74698D02*
X605736D01*
G01X611664Y-68865D02*
Y-51365D01*
X621708Y-68865D01*
Y-51365D01*
G01X634186Y-68865D02*
X632439Y-68573D01*
X630911Y-67407D01*
X629601Y-65657D01*
X628727Y-63615D01*
X628291Y-61282D01*
Y-58948D01*
X628727Y-56615D01*
X629601Y-54573D01*
X630911Y-52824D01*
X632439Y-51657D01*
X634186Y-51365D01*
X635932Y-51657D01*
X637461Y-52824D01*
X638771Y-54573D01*
X639645Y-56615D01*
X640081Y-58948D01*
Y-61282D01*
X639645Y-63615D01*
X638771Y-65657D01*
X637461Y-67407D01*
X635932Y-68573D01*
X634186Y-68865D01*
G01X555436Y-113865D02*
Y-96365D01*
X552816Y-99865D01*
G01Y-113865D02*
X558056D01*
G01X568133Y-110365D02*
X569442Y-112407D01*
X571189Y-113573D01*
X573154Y-113865D01*
X574901Y-113573D01*
X576648Y-112115D01*
X577739Y-110365D01*
X577958Y-108615D01*
X577521Y-106574D01*
X575993Y-105115D01*
X574464Y-104532D01*
X572499D01*
G01X574464D02*
X575774Y-103657D01*
X576866Y-102199D01*
X577303Y-100449D01*
X576866Y-98698D01*
X575774Y-97240D01*
X573809Y-96365D01*
X571844Y-96657D01*
X569879Y-97824D01*
G01X590436Y-113865D02*
Y-96365D01*
X587816Y-99865D01*
G01Y-113865D02*
X593056D01*
G01X603133Y-110365D02*
X604442Y-112407D01*
X606189Y-113573D01*
X608154Y-113865D01*
X609901Y-113573D01*
X611648Y-112115D01*
X612739Y-110365D01*
X612958Y-108615D01*
X612521Y-106574D01*
X610993Y-105115D01*
X609464Y-104532D01*
X607499D01*
G01X609464D02*
X610774Y-103657D01*
X611866Y-102199D01*
X612303Y-100449D01*
X611866Y-98698D01*
X610774Y-97240D01*
X608809Y-96365D01*
X606844Y-96657D01*
X604879Y-97824D01*
G01X625436Y-96365D02*
X623689Y-96948D01*
X622379Y-98407D01*
X621506Y-100156D01*
X620851Y-102490D01*
X620633Y-105115D01*
X620851Y-107740D01*
X621506Y-110074D01*
X622379Y-111824D01*
X623689Y-113282D01*
X625436Y-113865D01*
X627182Y-113282D01*
X628493Y-111824D01*
X629366Y-110074D01*
X630021Y-107740D01*
X630239Y-105115D01*
X630021Y-102490D01*
X629366Y-100156D01*
X628493Y-98407D01*
X627182Y-96948D01*
X625436Y-96365D01*
G01X685027Y-51365D02*
X690486Y-68865D01*
X695945Y-51365D01*
G01X712353Y-68865D02*
X703619D01*
Y-51365D01*
X712353D01*
G01X708859Y-59823D02*
X703619D01*
G01X721119Y-68865D02*
Y-51365D01*
X726578D01*
X728324Y-52240D01*
X729416Y-53407D01*
X729853Y-55740D01*
X729416Y-58074D01*
X728106Y-59532D01*
X726578Y-60407D01*
X721119D01*
G01X726578D02*
X729853Y-68865D01*
G01X742986Y-69448D02*
X742549Y-69157D01*
Y-68573D01*
X742986Y-68282D01*
X743423Y-68573D01*
Y-69157D01*
X742986Y-69448D01*
G01X707986Y-113865D02*
Y-96365D01*
X705366Y-99865D01*
G01Y-113865D02*
X710606D01*
G01X727232Y-104532D02*
X728106Y-103657D01*
X728761Y-102199D01*
X729198Y-100156D01*
X728761Y-98407D01*
X727888Y-97240D01*
X726359Y-96365D01*
X720464D01*
Y-113865D01*
X727669D01*
X729198Y-112699D01*
X730071Y-110948D01*
X730508Y-108907D01*
X730071Y-106865D01*
X728761Y-105115D01*
X727232Y-104532D01*
X720464D01*
G01X818569Y-51365D02*
Y-68865D01*
X827303D01*
G01X844366D02*
Y-57199D01*
G01Y-59240D02*
X843493Y-58074D01*
X842182Y-57490D01*
X840654Y-57199D01*
X839126Y-57782D01*
X837816Y-58948D01*
X836942Y-60698D01*
X836506Y-63032D01*
X836942Y-65365D01*
X837816Y-67115D01*
X839126Y-68282D01*
X840654Y-68865D01*
X842182Y-68573D01*
X843493Y-67699D01*
X844366Y-66532D01*
G01X853351Y-74115D02*
X854661Y-74698D01*
X856408Y-74115D01*
X857499Y-72949D01*
X858373Y-71490D01*
X859682Y-66824D01*
X862521Y-57199D01*
G01X855534D02*
X859682Y-66824D01*
G01X872161Y-60990D02*
X879148D01*
X878493Y-58948D01*
X877401Y-57782D01*
X875873Y-57199D01*
X874344Y-57490D01*
X873034Y-58365D01*
X872161Y-60407D01*
X871724Y-62157D01*
Y-63907D01*
X872161Y-65657D01*
X873253Y-67407D01*
X874563Y-68573D01*
X876091Y-68865D01*
X877619Y-68282D01*
X879148Y-66532D01*
G01X889879Y-68865D02*
Y-57199D01*
G01Y-59532D02*
X890971Y-58365D01*
X892063Y-57490D01*
X893591Y-57199D01*
X894682Y-57490D01*
X895993Y-58365D01*
G01X879803Y-96365D02*
Y-113865D01*
X871069D01*
G01X857936D02*
Y-96365D01*
X860556Y-99865D01*
G01Y-113865D02*
X855316D01*
G01X840436Y-96365D02*
X842183Y-96948D01*
X843493Y-98407D01*
X844366Y-100156D01*
X845021Y-102490D01*
X845239Y-105115D01*
X845021Y-107740D01*
X844366Y-110074D01*
X843493Y-111824D01*
X842183Y-113282D01*
X840436Y-113865D01*
X838690Y-113282D01*
X837379Y-111824D01*
X836506Y-110074D01*
X835851Y-107740D01*
X835633Y-105115D01*
X835851Y-102490D01*
X836506Y-100156D01*
X837379Y-98407D01*
X838690Y-96948D01*
X840436Y-96365D01*
G01X943619Y-110365D02*
X944711Y-112115D01*
X946021Y-113282D01*
X947549Y-113865D01*
X949296Y-113282D01*
X950606Y-112115D01*
X951916Y-110365D01*
X952353Y-108032D01*
Y-96365D01*
G01X965486Y-113865D02*
X963739Y-113573D01*
X962211Y-112407D01*
X960901Y-110657D01*
X960027Y-108615D01*
X959591Y-106282D01*
Y-103948D01*
X960027Y-101615D01*
X960901Y-99573D01*
X962211Y-97824D01*
X963739Y-96657D01*
X965486Y-96365D01*
X967232Y-96657D01*
X968761Y-97824D01*
X970071Y-99573D01*
X970945Y-101615D01*
X971381Y-103948D01*
Y-106282D01*
X970945Y-108615D01*
X970071Y-110657D01*
X968761Y-112407D01*
X967232Y-113573D01*
X965486Y-113865D01*
G01X978401Y-111532D02*
X980148Y-112990D01*
X982113Y-113865D01*
X983859D01*
X985606Y-112990D01*
X986916Y-111532D01*
X987571Y-109490D01*
X987134Y-107449D01*
X986043Y-105698D01*
X984078Y-104532D01*
X981458Y-103948D01*
X979929Y-102782D01*
X979274Y-100740D01*
X979711Y-98698D01*
X980803Y-97240D01*
X982331Y-96365D01*
X983859D01*
X985388Y-96948D01*
X986698Y-98407D01*
G01X1004853Y-113865D02*
X996119D01*
Y-96365D01*
X1004853D01*
G01X1001359Y-104823D02*
X996119D01*
G01X1013619Y-113865D02*
Y-96365D01*
X1018859D01*
X1020606Y-97240D01*
X1021916Y-99282D01*
X1022353Y-101615D01*
X1021916Y-103948D01*
X1020824Y-105698D01*
X1018859Y-106574D01*
X1013619D01*
G01X1030901Y-113865D02*
Y-96365D01*
G01X1040071D02*
Y-113865D01*
G01Y-105115D02*
X1030901D01*
G01X1066119Y-96365D02*
Y-113865D01*
X1074853D01*
G01X1082527D02*
X1087986Y-96365D01*
X1093445Y-113865D01*
G01X1091479Y-107740D02*
X1084492D01*
G01X1100683Y-96365D02*
Y-108907D01*
X1101556Y-111532D01*
X1103303Y-113282D01*
X1105486Y-113865D01*
X1107669Y-113282D01*
X1109416Y-111532D01*
X1110289Y-108907D01*
Y-96365D01*
G01X960683Y-68865D02*
Y-51365D01*
X965049D01*
X966796Y-52240D01*
X968106Y-53407D01*
X969198Y-55156D01*
X970071Y-57199D01*
X970289Y-60115D01*
X970071Y-63032D01*
X969198Y-65074D01*
X968106Y-66824D01*
X966796Y-67990D01*
X965049Y-68865D01*
X960683D01*
G01X979711Y-60990D02*
X986698D01*
X986043Y-58948D01*
X984951Y-57782D01*
X983423Y-57199D01*
X981894Y-57490D01*
X980584Y-58365D01*
X979711Y-60407D01*
X979274Y-62157D01*
Y-63907D01*
X979711Y-65657D01*
X980803Y-67407D01*
X982113Y-68573D01*
X983641Y-68865D01*
X985169Y-68282D01*
X986698Y-66532D01*
G01X997211Y-66824D02*
X998303Y-67990D01*
X999831Y-68865D01*
X1001141D01*
X1002451Y-68282D01*
X1003324Y-67407D01*
X1003761Y-66241D01*
X1003543Y-64490D01*
X1002669Y-63615D01*
X998739Y-61865D01*
X997866Y-59823D01*
X998303Y-58365D01*
X999176Y-57490D01*
X1000486Y-57199D01*
X1001796Y-57490D01*
X1003106Y-58365D01*
G01X1017986Y-57199D02*
Y-68865D01*
G01Y-52532D02*
X1017549Y-52240D01*
Y-51657D01*
X1017986Y-51365D01*
X1018423Y-51657D01*
Y-52240D01*
X1017986Y-52532D01*
G01X1032429Y-73240D02*
X1033958Y-74407D01*
X1035704Y-74698D01*
X1037232Y-74407D01*
X1038543Y-72949D01*
X1039416Y-70907D01*
Y-57199D01*
G01Y-59532D02*
X1038543Y-58365D01*
X1037232Y-57490D01*
X1035704Y-57199D01*
X1033958Y-57782D01*
X1032866Y-58948D01*
X1031992Y-60990D01*
X1031556Y-63032D01*
X1031774Y-64782D01*
X1032648Y-66824D01*
X1033958Y-68282D01*
X1035704Y-68865D01*
X1037014Y-68573D01*
X1038543Y-67407D01*
X1039416Y-66241D01*
G01X1049274Y-68865D02*
Y-57199D01*
G01Y-60115D02*
X1050148Y-58657D01*
X1051458Y-57490D01*
X1053204Y-57199D01*
X1054732Y-57490D01*
X1056043Y-58657D01*
X1056698Y-60698D01*
Y-68865D01*
G01X1067211Y-60990D02*
X1074198D01*
X1073543Y-58948D01*
X1072451Y-57782D01*
X1070923Y-57199D01*
X1069394Y-57490D01*
X1068084Y-58365D01*
X1067211Y-60407D01*
X1066774Y-62157D01*
Y-63907D01*
X1067211Y-65657D01*
X1068303Y-67407D01*
X1069613Y-68573D01*
X1071141Y-68865D01*
X1072669Y-68282D01*
X1074198Y-66532D01*
G01X1084929Y-68865D02*
Y-57199D01*
G01Y-59532D02*
X1086021Y-58365D01*
X1087113Y-57490D01*
X1088641Y-57199D01*
X1089732Y-57490D01*
X1091043Y-58365D01*
G01X1131686Y-113865D02*
Y-96365D01*
X1129066Y-99865D01*
G01Y-113865D02*
X1134306D01*
G01X1149186D02*
Y-96365D01*
X1146566Y-99865D01*
G01Y-113865D02*
X1151806D01*
G01X1162756Y-114448D02*
X1170616Y-96365D01*
G01X1184186Y-113865D02*
Y-96365D01*
X1181566Y-99865D01*
G01Y-113865D02*
X1186806D01*
G01X1196883Y-110365D02*
X1198192Y-112407D01*
X1199939Y-113573D01*
X1201904Y-113865D01*
X1203651Y-113573D01*
X1205398Y-112115D01*
X1206489Y-110365D01*
X1206708Y-108615D01*
X1206271Y-106574D01*
X1204743Y-105115D01*
X1203214Y-104532D01*
X1201249D01*
G01X1203214D02*
X1204524Y-103657D01*
X1205616Y-102199D01*
X1206053Y-100449D01*
X1205616Y-98698D01*
X1204524Y-97240D01*
X1202559Y-96365D01*
X1200594Y-96657D01*
X1198629Y-97824D01*
G01X1215256Y-114448D02*
X1223116Y-96365D01*
G01X1232538Y-99282D02*
X1233848Y-97532D01*
X1235376Y-96657D01*
X1237123Y-96365D01*
X1239306Y-96948D01*
X1240834Y-98407D01*
X1241271Y-100156D01*
X1241053Y-101907D01*
X1240179Y-103365D01*
X1235813Y-106282D01*
X1233848Y-108323D01*
X1232538Y-111241D01*
X1232101Y-113865D01*
X1241271D01*
G01X1254186Y-96365D02*
X1252439Y-96948D01*
X1251129Y-98407D01*
X1250256Y-100156D01*
X1249601Y-102490D01*
X1249383Y-105115D01*
X1249601Y-107740D01*
X1250256Y-110074D01*
X1251129Y-111824D01*
X1252439Y-113282D01*
X1254186Y-113865D01*
X1255932Y-113282D01*
X1257243Y-111824D01*
X1258116Y-110074D01*
X1258771Y-107740D01*
X1258989Y-105115D01*
X1258771Y-102490D01*
X1258116Y-100156D01*
X1257243Y-98407D01*
X1255932Y-96948D01*
X1254186Y-96365D01*
G01X1271686Y-113865D02*
Y-96365D01*
X1269066Y-99865D01*
G01Y-113865D02*
X1274306D01*
G01X1291806D02*
Y-96365D01*
X1283727Y-108907D01*
X1294645D01*
G01X1179383Y-68865D02*
Y-51365D01*
X1183749D01*
X1185496Y-52240D01*
X1186806Y-53407D01*
X1187898Y-55156D01*
X1188771Y-57199D01*
X1188989Y-60115D01*
X1188771Y-63032D01*
X1187898Y-65074D01*
X1186806Y-66824D01*
X1185496Y-67990D01*
X1183749Y-68865D01*
X1179383D01*
G01X1205616D02*
Y-57199D01*
G01Y-59240D02*
X1204743Y-58074D01*
X1203432Y-57490D01*
X1201904Y-57199D01*
X1200376Y-57782D01*
X1199066Y-58948D01*
X1198192Y-60698D01*
X1197756Y-63032D01*
X1198192Y-65365D01*
X1199066Y-67115D01*
X1200376Y-68282D01*
X1201904Y-68865D01*
X1203432Y-68573D01*
X1204743Y-67699D01*
X1205616Y-66532D01*
G01X1219186Y-51365D02*
Y-68865D01*
G01X1216129Y-57199D02*
X1222243D01*
G01X1233411Y-60990D02*
X1240398D01*
X1239743Y-58948D01*
X1238651Y-57782D01*
X1237123Y-57199D01*
X1235594Y-57490D01*
X1234284Y-58365D01*
X1233411Y-60407D01*
X1232974Y-62157D01*
Y-63907D01*
X1233411Y-65657D01*
X1234503Y-67407D01*
X1235813Y-68573D01*
X1237341Y-68865D01*
X1238869Y-68282D01*
X1240398Y-66532D01*
G01X615103Y30690D02*
Y30703D01*
X616844Y32444D01*
Y41300D01*
X609045Y49099D01*
X546500D01*
X546499Y49100D01*
X541800D01*
X539300Y51600D01*
Y55700D01*
X534100Y60900D01*
X530010D01*
X529410Y61500D01*
Y62409D01*
X528810Y63009D01*
X527610D01*
X527010Y62409D01*
Y61500D01*
X526410Y60900D01*
X525210D01*
X524610Y61500D01*
Y62409D01*
X524010Y63009D01*
X522810D01*
X522210Y62409D01*
Y61500D01*
X521610Y60900D01*
X520410D01*
X519810Y61500D01*
Y62409D01*
X519210Y63009D01*
X518010D01*
X517410Y62409D01*
Y61500D01*
X516810Y60900D01*
X515610D01*
X515010Y61500D01*
Y62409D01*
X514410Y63009D01*
X513210D01*
X512610Y62409D01*
Y61500D01*
X512010Y60900D01*
X447286D01*
X428686Y79500D01*
X403900D01*
X402050Y81350D01*
Y102064D01*
G01X616600Y12307D02*
X616746Y12453D01*
Y12553D01*
X621430Y17237D01*
Y26537D01*
X622302Y27410D01*
Y32442D01*
X622300Y32444D01*
Y34439D01*
X622700Y34839D01*
Y45203D01*
X611903Y56000D01*
X548200D01*
X546300Y57900D01*
Y68400D01*
X544465Y70235D01*
X494437D01*
X493572Y71100D01*
X490529D01*
X489664Y70235D01*
X484618D01*
X483753Y71100D01*
X473950D01*
X473200Y70350D01*
Y68750D01*
X472450Y68000D01*
X471050D01*
X470400Y68650D01*
Y70500D01*
X469800Y71100D01*
X467945D01*
X467345Y70500D01*
Y68600D01*
X466745Y68000D01*
X465545D01*
X464945Y68600D01*
Y70500D01*
X464345Y71100D01*
X463145D01*
X462545Y70500D01*
Y68600D01*
X461945Y68000D01*
X460745D01*
X460145Y68600D01*
Y70500D01*
X459545Y71100D01*
X458345D01*
X457745Y70500D01*
Y68600D01*
X457145Y68000D01*
X455945D01*
X455345Y68600D01*
Y70500D01*
X454745Y71100D01*
X453545D01*
X452945Y70500D01*
Y68600D01*
X452345Y68000D01*
X451145D01*
X450545Y68600D01*
Y70500D01*
X449945Y71100D01*
X446845D01*
X424600Y93345D01*
Y97900D01*
X409575Y112925D01*
X404675D01*
X403375Y114225D01*
G03X401478Y114422I-1897J-9035D01*
G02X400098Y115040I1422J5025D01*
G02X399400Y117200I2993J2160D01*
G03X398762Y118462I-1567J0D01*
G01X396276Y120948D01*
G01X618900Y33290D02*
Y42497D01*
X609997Y51400D01*
X543700D01*
X541700Y53400D01*
Y63300D01*
X539365Y65635D01*
X511100D01*
X510500Y65035D01*
Y64000D01*
X509900Y63400D01*
X508300D01*
X507700Y64000D01*
Y65035D01*
X507100Y65635D01*
X505650D01*
X505050Y65035D01*
Y63800D01*
X504450Y63200D01*
X503250D01*
X502650Y63800D01*
Y65035D01*
X502050Y65635D01*
X500850D01*
X500250Y65035D01*
Y63800D01*
X499650Y63200D01*
X498450D01*
X497850Y63800D01*
Y65035D01*
X497250Y65635D01*
X496050D01*
X495450Y65035D01*
Y63800D01*
X494850Y63200D01*
X493650D01*
X493050Y63800D01*
Y65035D01*
X492450Y65635D01*
X490150D01*
X489400Y64885D01*
Y64050D01*
X488650Y63300D01*
X448139D01*
X429939Y81500D01*
X406800D01*
X405400Y82900D01*
Y101007D01*
X403803Y102604D01*
G01X616707Y15616D02*
X617957Y16866D01*
Y27642D01*
X619455Y29140D01*
X619561D01*
X620600Y30179D01*
Y44050D01*
X610950Y53700D01*
X546300D01*
X544000Y56000D01*
Y65900D01*
X541965Y67935D01*
X488035D01*
X487435Y67335D01*
Y66200D01*
X486835Y65600D01*
X485635D01*
X485035Y66200D01*
Y67335D01*
X484435Y67935D01*
X482135D01*
X481500Y67300D01*
Y66450D01*
X480750Y65700D01*
X448992D01*
X448200Y66492D01*
Y68050D01*
X447450Y68800D01*
X445892D01*
X431192Y83500D01*
X409950D01*
X409100Y84350D01*
Y104624D01*
X405537Y108187D01*
G01X439388Y156600D02*
X487300D01*
X499021Y156545D01*
X503140D01*
X503159Y156526D01*
X617250Y155991D01*
X621633D01*
X642428Y140529D01*
X661729Y121228D01*
X713300Y65000D01*
X719000Y51000D01*
X723565Y42335D01*
Y30137D01*
X723500Y30072D01*
Y29907D01*
G01X662503Y33207D02*
Y43109D01*
X666901Y47507D01*
Y54605D01*
X648756Y72750D01*
X632429D01*
X629200Y75979D01*
Y78550D01*
X628600Y79150D01*
X626050D01*
X625099Y80101D01*
Y80949D01*
X628701Y84551D01*
Y85399D01*
X627851Y86249D01*
X627003D01*
X623401Y82647D01*
X622553D01*
X620924Y84276D01*
Y85124D01*
X624426Y88626D01*
Y89474D01*
X623474Y90426D01*
X622626D01*
X619140Y86940D01*
X618239D01*
X617307Y87872D01*
Y89107D01*
X618200Y90000D01*
Y91007D01*
X606508Y102699D01*
X452001D01*
X450300Y104400D01*
Y107207D01*
X438903Y118604D01*
X436425D01*
X435825Y118004D01*
Y117400D01*
X435225Y116800D01*
X434600D01*
X433500Y117900D01*
Y120600D01*
X434100Y121200D01*
X437000D01*
X437400Y121600D01*
G01X657900Y30690D02*
X657917Y30707D01*
X657966D01*
X659703Y32444D01*
Y33936D01*
X659000Y34639D01*
Y42806D01*
X662301Y46107D01*
Y52699D01*
X647525Y67475D01*
X631198D01*
X619948Y78725D01*
X615600D01*
X615000Y79325D01*
Y83673D01*
X611541Y87132D01*
Y87980D01*
X612707Y89146D01*
Y89994D01*
X611857Y90844D01*
X611009D01*
X609843Y89678D01*
X608995D01*
X608145Y90528D01*
Y91376D01*
X609311Y92542D01*
Y93390D01*
X608461Y94240D01*
X607613D01*
X606447Y93074D01*
X605599D01*
X604749Y93924D01*
Y94772D01*
X605915Y95938D01*
Y96786D01*
X605065Y97636D01*
X604217D01*
X603051Y96470D01*
X602203D01*
X600574Y98099D01*
X450902D01*
X449539Y99462D01*
X449538D01*
X446128Y102872D01*
Y106844D01*
X441622Y111350D01*
X435734D01*
X433100Y113984D01*
Y116800D01*
X432079Y117821D01*
Y120180D01*
X428255Y124004D01*
Y126236D01*
G01X721747Y32954D02*
X721880Y33087D01*
Y40620D01*
X711119Y51381D01*
Y63776D01*
X657775Y121927D01*
X651679Y128024D01*
X641601Y138102D01*
X621170Y153201D01*
X619266D01*
X619265Y153200D01*
X505300D01*
X504100Y152000D01*
X463519D01*
X462919Y152600D01*
Y153900D01*
X462319Y154500D01*
X461119D01*
X460519Y153900D01*
Y152600D01*
X459919Y152000D01*
X458719D01*
X458119Y152600D01*
Y154100D01*
X457519Y154700D01*
X456319D01*
X455719Y154100D01*
Y152600D01*
X455119Y152000D01*
X453919D01*
X453319Y152600D01*
Y154100D01*
X452719Y154700D01*
X451519D01*
X450919Y154100D01*
Y152600D01*
X450319Y152000D01*
X442100D01*
X440100Y150000D01*
X430400D01*
G01X665901Y12307D02*
X664301Y10707D01*
X660704D01*
X659697Y11714D01*
Y13250D01*
X658643Y14304D01*
X657100D01*
X656501Y14903D01*
Y18158D01*
X657650Y19307D01*
Y27511D01*
X659900Y29761D01*
Y31226D01*
X660703Y32029D01*
Y42909D01*
X664601Y46807D01*
Y53652D01*
X648478Y69775D01*
X632151D01*
X620901Y81025D01*
X618275D01*
X617300Y82000D01*
Y84626D01*
X615007Y86919D01*
Y90947D01*
X605555Y100399D01*
X451301D01*
X448451Y103249D01*
Y106752D01*
X438803Y116400D01*
X438500D01*
G01X662359Y12379D02*
X662221D01*
X660468Y14132D01*
Y17175D01*
X662500Y19207D01*
X663788D01*
X665000Y20419D01*
Y27705D01*
X666328Y29033D01*
Y34541D01*
X666100Y34769D01*
Y41891D01*
X670216Y46007D01*
X672501D01*
X673901Y47407D01*
Y57364D01*
X651615Y79650D01*
X637800D01*
X636200Y81250D01*
Y88141D01*
X614741Y109600D01*
X612837D01*
X612836Y109599D01*
X454401D01*
X443176Y120824D01*
X442842D01*
G01X661708Y30699D02*
X661716Y30707D01*
X662743D01*
X664303Y32267D01*
Y33736D01*
X664100Y33939D01*
Y42806D01*
X669301Y48007D01*
Y55458D01*
X649709Y75050D01*
X633450D01*
X631600Y76900D01*
Y86235D01*
X624285Y93550D01*
X622250D01*
X621200Y92500D01*
X620534D01*
X619004Y94030D01*
Y94878D01*
X620639Y96513D01*
Y97196D01*
X619624Y98211D01*
X618941D01*
X617306Y96576D01*
X616458D01*
X615608Y97426D01*
Y98274D01*
X616843Y99509D01*
Y100357D01*
X615993Y101207D01*
X615145D01*
X613910Y99972D01*
X613062D01*
X612212Y100822D01*
Y101670D01*
X613447Y102905D01*
Y103753D01*
X612597Y104603D01*
X611749D01*
X610514Y103368D01*
X609666D01*
X608035Y104999D01*
X453923D01*
X439400Y119522D01*
Y120100D01*
G01X664678Y30307D02*
X665303Y30932D01*
Y34151D01*
X665100Y34354D01*
Y42306D01*
X669851Y47057D01*
X670951D01*
X671601Y47707D01*
Y56411D01*
X650662Y77350D01*
X636250D01*
X633900Y79700D01*
Y87188D01*
X613789Y107299D01*
X454174D01*
X443086Y118387D01*
G01X662192Y14874D02*
X662300Y14982D01*
Y17053D01*
X663318Y18071D01*
X664464D01*
X666300Y19907D01*
Y27590D01*
X667328Y28618D01*
Y41704D01*
X670631Y45007D01*
X673901D01*
X676201Y47307D01*
Y58317D01*
X652568Y81950D01*
X640450D01*
X639700Y82700D01*
Y87894D01*
X615194Y112400D01*
X454800D01*
X444242Y122958D01*
Y124324D01*
G01X666175Y14807D02*
X667700Y18807D01*
Y27575D01*
X668328Y28203D01*
Y41289D01*
X671046Y44007D01*
X675101D01*
X678501Y47407D01*
Y59270D01*
X623071Y114700D01*
X454500D01*
X451750Y117450D01*
X446079Y124680D01*
X444629Y126130D01*
X439100D01*
X435442Y124024D01*
G01X712182Y14124D02*
Y14125D01*
X711300Y15007D01*
Y17207D01*
X698900Y29607D01*
Y39282D01*
X693982Y44200D01*
Y58667D01*
X624349Y128300D01*
X608546D01*
X607946Y127700D01*
Y127300D01*
X607346Y126700D01*
X606146D01*
X605546Y127300D01*
Y127700D01*
X604946Y128300D01*
X585700D01*
X584100Y126700D01*
X580800D01*
X579200Y128300D01*
X576100D01*
X573700Y125900D01*
X568944D01*
X567744Y127100D01*
X566544D01*
X565344Y125900D01*
X557000D01*
X556400Y126500D01*
Y127853D01*
X555800Y128453D01*
X554600D01*
X554000Y127853D01*
Y126500D01*
X553400Y125900D01*
X552200D01*
X551600Y126500D01*
Y127853D01*
X551000Y128453D01*
X549800D01*
X549200Y127853D01*
Y126500D01*
X548600Y125900D01*
X546300D01*
X540100Y132100D01*
X474100D01*
X470500Y135700D01*
X451800D01*
X449400Y133300D01*
X436494D01*
G01X720100Y14707D02*
Y14957D01*
X718650Y16407D01*
X715800D01*
X704800Y27407D01*
Y30609D01*
X702780Y32629D01*
Y38820D01*
X696282Y45318D01*
Y59620D01*
X625149Y130753D01*
X548753D01*
X545106Y134400D01*
X511205D01*
X510605Y135000D01*
Y137600D01*
X510005Y138200D01*
X508805D01*
X508205Y137600D01*
Y135000D01*
X507605Y134400D01*
X506405D01*
X505805Y135000D01*
Y136800D01*
X505205Y137400D01*
X504005D01*
X503405Y136800D01*
Y135000D01*
X502805Y134400D01*
X501605D01*
X501005Y135000D01*
Y136200D01*
X500405Y136800D01*
X499205D01*
X498605Y136200D01*
Y135000D01*
X498005Y134400D01*
X475053D01*
X473227Y136227D01*
X473226D01*
X471153Y138300D01*
X467300D01*
X466400Y137400D01*
X463400D01*
X461900Y138900D01*
X460000D01*
X458500Y137400D01*
X456168D01*
X455568Y138000D01*
Y139000D01*
X454968Y139600D01*
X453768D01*
X453168Y139000D01*
Y138000D01*
X452568Y137400D01*
X449800D01*
X447700Y135300D01*
X436000D01*
G01X436900Y131700D02*
X470300D01*
X472200Y129800D01*
X485064D01*
X485664Y129200D01*
Y128000D01*
X486264Y127400D01*
X487464D01*
X488064Y128000D01*
Y129200D01*
X488664Y129800D01*
X489864D01*
X490464Y129200D01*
Y127900D01*
X491064Y127300D01*
X492264D01*
X492864Y127900D01*
Y129200D01*
X493464Y129800D01*
X538500D01*
X545750Y122550D01*
X598850D01*
X600700Y124400D01*
X614700D01*
X616300Y122800D01*
X626596D01*
X691682Y57714D01*
Y39518D01*
X696500Y34700D01*
Y28500D01*
X708900Y16100D01*
Y12507D01*
X709000Y12407D01*
G01X708900Y30407D02*
X709240Y30747D01*
Y37930D01*
X698900Y48270D01*
Y60902D01*
X623102Y136700D01*
X591100D01*
X590600Y136200D01*
Y135300D01*
X590000Y134700D01*
X588800D01*
X588200Y135300D01*
Y136000D01*
X587700Y136500D01*
X586100D01*
X585600Y136000D01*
Y135300D01*
X585000Y134700D01*
X583800D01*
X583200Y135300D01*
X580800D01*
X580200Y134700D01*
X575947D01*
X574300Y133053D01*
X550500D01*
X549900Y133653D01*
Y136100D01*
X549300Y136700D01*
X516100D01*
X512100Y140700D01*
X496305D01*
X495705Y140100D01*
Y138400D01*
X495105Y137800D01*
X493905D01*
X493305Y138400D01*
Y140100D01*
X492705Y140700D01*
X491505D01*
X490905Y140100D01*
Y137800D01*
X490305Y137200D01*
X489105D01*
X488505Y137800D01*
Y140100D01*
X487905Y140700D01*
X486705D01*
X486105Y140100D01*
Y137800D01*
X485505Y137200D01*
X484305D01*
X483705Y137800D01*
Y140100D01*
X483105Y140700D01*
X481905D01*
X481305Y140100D01*
Y138800D01*
X480705Y138200D01*
X479505D01*
X478905Y138800D01*
Y140100D01*
X478305Y140700D01*
X450000D01*
X447100Y137800D01*
X436300D01*
G01X437103Y139503D02*
X446297D01*
X449794Y143000D01*
X514600D01*
X518600Y139000D01*
X538995D01*
X539595Y139600D01*
Y141410D01*
X540195Y142010D01*
X541395D01*
X541995Y141410D01*
Y139600D01*
X542595Y139000D01*
X543795D01*
X544395Y139600D01*
Y141410D01*
X544995Y142010D01*
X546195D01*
X546795Y141410D01*
Y139600D01*
X547395Y139000D01*
X548595D01*
X549195Y139600D01*
Y141700D01*
X549795Y142300D01*
X550995D01*
X551595Y141700D01*
Y139600D01*
X552195Y139000D01*
X553500D01*
X554500Y140000D01*
Y140900D01*
X555100Y141500D01*
X556891D01*
X559391Y139000D01*
X568200D01*
X568800Y139600D01*
Y142000D01*
X569400Y142600D01*
X570600D01*
X571200Y142000D01*
Y139600D01*
X571800Y139000D01*
X615600D01*
X616200Y139600D01*
Y141600D01*
X616800Y142200D01*
X618000D01*
X618600Y141600D01*
Y139600D01*
X619200Y139000D01*
X624055D01*
X702300Y60755D01*
Y47860D01*
X710720Y39440D01*
Y32387D01*
X712171Y30936D01*
X712271D01*
X712400Y30807D01*
G01X723586Y14080D02*
Y14121D01*
X723200Y14507D01*
Y25207D01*
X719424Y28983D01*
Y31731D01*
X720000Y32307D01*
Y38800D01*
X708306Y50494D01*
Y62812D01*
X620218Y150900D01*
X529942D01*
X529342Y150300D01*
Y149200D01*
X528742Y148600D01*
X527542D01*
X526942Y149200D01*
Y150300D01*
X526342Y150900D01*
X518247D01*
X517047Y149700D01*
X447300D01*
X444400Y146800D01*
X440300D01*
X438988Y148112D01*
X437900D01*
G01X436644Y143500D02*
X438370Y141774D01*
X444781D01*
X448307Y145300D01*
X517644D01*
X521644Y141300D01*
X530556D01*
X531800Y142544D01*
Y144644D01*
X532356Y145200D01*
X534156D01*
X534646Y144710D01*
X536446D01*
X536936Y145200D01*
X538736D01*
X539226Y144710D01*
X541026D01*
X541516Y145200D01*
X543316D01*
X543806Y144710D01*
X545606D01*
X546096Y145200D01*
X558144D01*
X558800Y144544D01*
Y142844D01*
X560044Y141600D01*
X564656D01*
X565900Y142844D01*
Y144600D01*
X566500Y145200D01*
X577044D01*
X577900Y144344D01*
Y143244D01*
X579544Y141600D01*
X587144D01*
X587444Y141300D01*
X600156D01*
X601656Y142800D01*
X605844D01*
X607344Y141300D01*
X610231D01*
X613900Y144969D01*
X621339D01*
X704606Y61702D01*
Y48894D01*
X714100Y39400D01*
Y27307D01*
X716182Y25225D01*
Y23999D01*
X715090Y22907D01*
G01X437300Y144400D02*
X438826Y142874D01*
X444325D01*
X447851Y146400D01*
X518100D01*
X522100Y142400D01*
X530100D01*
X530700Y143000D01*
Y145100D01*
X531900Y146300D01*
X558600D01*
X559900Y145000D01*
Y143300D01*
X560500Y142700D01*
X564200D01*
X564800Y143300D01*
Y145056D01*
X566044Y146300D01*
X577500D01*
X579000Y144800D01*
Y143700D01*
X580000Y142700D01*
X587600D01*
X587900Y142400D01*
X599700D01*
X601200Y143900D01*
X606300D01*
X607800Y142400D01*
X609775D01*
X613444Y146069D01*
X621795D01*
X705706Y62158D01*
Y49350D01*
X715200Y39856D01*
Y27763D01*
X717282Y25681D01*
Y24000D01*
X718375Y22907D01*
G54D13*
X457913Y45276D03*
X477913D03*
G54D23*
G01X57009Y230009D02*
X57011Y230007D01*
X60493D01*
X90575Y199925D01*
X111425D01*
X116125Y204625D01*
X119224D01*
X127899Y213300D01*
X155000D01*
X157100Y211200D01*
X160000D01*
X161700Y212900D01*
X186111D01*
X189376Y209635D01*
Y190890D01*
X195230Y185036D01*
X203636D01*
X207140Y188540D01*
X207861D01*
G01X94000Y63300D02*
X92725Y64575D01*
Y76936D01*
X94289Y78500D01*
X101767D01*
X114725Y91458D01*
Y117696D01*
X120229Y123200D01*
X131074D01*
X134725Y126851D01*
Y127036D01*
X144509Y136820D01*
X147136D01*
X157500Y147184D01*
Y149025D01*
G01X135412Y141400D02*
X134189D01*
X122020Y129231D01*
X116214D01*
X111025Y124042D01*
Y93080D01*
X100145Y82200D01*
X92755D01*
X88750Y78195D01*
Y76550D01*
X79700Y67500D01*
G01X133975Y129141D02*
X130679D01*
X128919Y127381D01*
X116981D01*
X112875Y123275D01*
Y92225D01*
X101000Y80350D01*
X93522D01*
X90600Y77428D01*
Y63200D01*
G01X109600Y63700D02*
X109425Y63875D01*
Y67936D01*
X110464Y68975D01*
X118460D01*
X132425Y82940D01*
Y86836D01*
X133589Y88000D01*
X137078D01*
X144700Y95622D01*
Y118841D01*
X170734Y144875D01*
X176700D01*
G01X175787Y127000D02*
Y126058D01*
X156330Y106601D01*
Y101030D01*
X150813Y95513D01*
Y92698D01*
X119625Y61510D01*
Y59364D01*
X121875Y57114D01*
Y42575D01*
X120000Y40700D01*
G01X291201Y225025D02*
Y224423D01*
X273078Y206300D01*
X264070D01*
X263195Y205425D01*
X250125D01*
X244251Y199551D01*
Y194834D01*
X242417Y193000D01*
X237078D01*
X227825Y183747D01*
Y178055D01*
X221352Y171582D01*
Y154542D01*
X208510Y141700D01*
X202675D01*
X166480Y105505D01*
Y89415D01*
X155346Y78281D01*
X149633D01*
X138574Y67222D01*
Y57924D01*
G01X136600Y44800D02*
X132500D01*
X128625Y48675D01*
Y61336D01*
X129689Y62400D01*
X131135D01*
X148866Y80131D01*
X154579D01*
X164500Y90052D01*
Y106142D01*
X201908Y143550D01*
X207743D01*
X219502Y155309D01*
Y172349D01*
X225975Y178822D01*
Y184514D01*
X236361Y194900D01*
X241700D01*
X242400Y195600D01*
Y200620D01*
X249055Y207275D01*
X262428D01*
X263303Y208150D01*
X272311D01*
X287802Y223641D01*
Y225200D01*
G01X434900Y6925D02*
X420967D01*
X419661Y8231D01*
Y46075D01*
X413597Y52139D01*
X379639D01*
X378275Y50775D01*
X360421D01*
X357122Y47476D01*
X349078D01*
X346704Y49850D01*
X337940D01*
X333765Y45675D01*
X321206D01*
X320225Y44694D01*
Y43306D01*
X320573Y42958D01*
Y36653D01*
X318245Y34325D01*
X252772D01*
X251597Y35500D01*
X152872D01*
X148880Y39492D01*
Y51930D01*
X149610Y52660D01*
X151515D01*
X151654Y52754D01*
X152471Y53571D01*
X152500Y53614D01*
Y58111D01*
X185200Y90811D01*
Y104200D01*
X187500Y106500D01*
G01X183726Y106353D02*
Y96983D01*
X181200Y94457D01*
Y88800D01*
X149600Y57200D01*
X147732D01*
X145630Y55098D01*
Y39470D01*
X151625Y33475D01*
X318598D01*
X324000Y38877D01*
Y39075D01*
X327595Y42670D01*
X327646Y42680D01*
X334680D01*
X338876Y46876D01*
X344824D01*
X355733Y35967D01*
X380802D01*
X386400Y41565D01*
Y44883D01*
X390756Y49239D01*
X412394D01*
X416561Y45072D01*
Y7228D01*
X419989Y3800D01*
X444099D01*
X446199Y5900D01*
X446200D01*
G01X226500Y94450D02*
X226900Y94050D01*
Y68159D01*
X226675Y67934D01*
Y45575D01*
X229300Y42950D01*
G01X438300Y6925D02*
X436525Y8700D01*
X435114D01*
X431439Y12375D01*
X425153D01*
X421211Y16317D01*
Y47001D01*
X414323Y53889D01*
X379196D01*
X377632Y52325D01*
X359778D01*
X356479Y49026D01*
X349721D01*
X347197Y51550D01*
X337447D01*
X332597Y46700D01*
X321028D01*
X319375Y45047D01*
Y42953D01*
X319723Y42605D01*
Y37006D01*
X317892Y35175D01*
X253125D01*
X238900Y49400D01*
X232500D01*
X228225Y53675D01*
Y67291D01*
X231450Y70516D01*
Y83550D01*
X230425Y84575D01*
Y100950D01*
X235075Y105600D01*
G01X221400Y64500D02*
X224725Y67825D01*
Y96961D01*
X227800Y100036D01*
Y101200D01*
G01X426405Y25054D02*
X426375D01*
Y46223D01*
X415609Y56989D01*
X377910D01*
X376346Y55425D01*
X358068D01*
X354769Y52126D01*
X351431D01*
X348907Y54650D01*
X332347D01*
X328097Y50400D01*
X319689D01*
X318000Y48711D01*
Y40067D01*
X317971Y40024D01*
X313972Y36025D01*
X262406D01*
X241975Y56456D01*
Y62291D01*
X245209Y65525D01*
X245836D01*
X252505Y72194D01*
Y74453D01*
X250558Y76400D01*
Y162687D01*
X255400Y167529D01*
Y173089D01*
X268611Y186300D01*
X271600D01*
X273060Y187760D01*
Y189374D01*
G01X241200Y94900D02*
X242475Y93625D01*
Y75975D01*
X237475Y70975D01*
Y57225D01*
X244100Y50600D01*
X244400D01*
G01X250300Y73800D02*
X248708Y75392D01*
Y163454D01*
X253500Y168246D01*
Y174360D01*
G01X276910Y189400D02*
Y188693D01*
X272667Y184450D01*
X270450D01*
X259462Y173462D01*
Y168974D01*
X252408Y161920D01*
Y77167D01*
X253700Y75875D01*
G01X430000Y34158D02*
X430225Y34383D01*
Y47607D01*
X417143Y60689D01*
X376376D01*
X374812Y59125D01*
X333889D01*
X320657Y72357D01*
Y75186D01*
X307800Y88043D01*
Y98128D01*
X305035Y100893D01*
Y111391D01*
X302724Y113702D01*
Y142541D01*
X312842Y152659D01*
Y154964D01*
X309000Y158806D01*
G01X437061Y10393D02*
Y13339D01*
X431775Y18625D01*
Y48250D01*
X417786Y62239D01*
X375733D01*
X374169Y60675D01*
X339325D01*
X330132Y69868D01*
X328146D01*
X327107Y70907D01*
Y70929D01*
X308900Y89136D01*
Y98500D01*
X305993Y101407D01*
Y111494D01*
X303575Y113912D01*
Y123175D01*
X306807Y126407D01*
Y129492D01*
X307854Y130539D01*
G01X336800Y164434D02*
X335895Y165339D01*
Y165351D01*
X335061Y166185D01*
X329563D01*
X329213Y165835D01*
Y163850D01*
X328863Y163500D01*
X328163D01*
X327813Y163850D01*
Y165835D01*
X327463Y166185D01*
X326185D01*
X322327Y162327D01*
Y161833D01*
X323832Y160327D01*
Y159833D01*
X323336Y159337D01*
X322842D01*
X321337Y160843D01*
X320843D01*
X320347Y160347D01*
Y159853D01*
X321060Y159140D01*
Y158560D01*
X320649Y158149D01*
X320071D01*
X316400Y161822D01*
X315822D01*
X315000Y161000D01*
Y150500D01*
X307500Y143000D01*
Y141000D01*
X308500Y140000D01*
X310000D01*
X315000Y135000D01*
Y130950D01*
X314550Y130500D01*
X312450D01*
X312000Y130050D01*
Y128000D01*
X310600Y126600D01*
Y125100D01*
X311300Y124400D01*
X312800D01*
X313500Y123700D01*
Y121800D01*
X312700Y121000D01*
Y118800D01*
X315200Y116300D01*
Y114500D01*
X313700Y113000D01*
X310000D01*
X309000Y112000D01*
Y110500D01*
X310100Y109400D01*
Y108000D01*
X309000Y106900D01*
Y105718D01*
X309410Y105308D01*
X313625D01*
X313975Y104958D01*
Y104258D01*
X313625Y103908D01*
X309410D01*
X309000Y103498D01*
Y102918D01*
X309410Y102508D01*
X313625D01*
X313975Y102158D01*
Y99086D01*
X313625Y98736D01*
X312200D01*
X311800Y98336D01*
Y97736D01*
X312200Y97336D01*
X313625D01*
X313975Y96986D01*
Y96286D01*
X313625Y95936D01*
X312300D01*
X311900Y95536D01*
Y94936D01*
X312300Y94536D01*
X313625D01*
X313975Y94186D01*
Y91825D01*
X314844Y90956D01*
X317641D01*
G01X303610Y110800D02*
X300700Y113710D01*
Y142850D01*
G01X339300Y174100D02*
Y174000D01*
X336800Y171500D01*
X324744D01*
X323756Y170512D01*
X321812D01*
X313800Y162500D01*
Y151300D01*
X304400Y141900D01*
Y128600D01*
X304149Y128349D01*
G01X427000Y17000D02*
X428225Y18225D01*
Y46990D01*
X416376Y58839D01*
X377143D01*
X375579Y57275D01*
X357301D01*
X354002Y53976D01*
X352198D01*
X349674Y56500D01*
X331511D01*
X328225Y53214D01*
X323303D01*
X320885Y55632D01*
Y58098D01*
X319897Y59086D01*
X315103D01*
X313400Y57383D01*
Y52250D01*
X311950Y50800D01*
G01X321900Y44000D02*
X322000Y43900D01*
X333900D01*
X338500Y48500D01*
X346144D01*
X348944Y45700D01*
X357256D01*
X360981Y49425D01*
X378835D01*
X380199Y50789D01*
X413037D01*
X418111Y45715D01*
Y7588D01*
X420549Y5150D01*
X442939D01*
X445464Y7675D01*
X447825D01*
X449600Y5900D01*
G01X346944Y156775D02*
Y154428D01*
X340000Y147484D01*
Y146000D01*
X337650Y143650D01*
X334030D01*
X333160Y142780D01*
Y141220D01*
X332523Y140583D01*
X326455D01*
X324321Y138449D01*
Y132512D01*
X321582Y129773D01*
Y127081D01*
X323500Y125163D01*
Y100059D01*
X321695Y98254D01*
Y91099D01*
X323275Y89519D01*
Y85416D01*
X339378Y69313D01*
X343595D01*
X348134Y64775D01*
X372468D01*
X374032Y66339D01*
X419487D01*
X436100Y49726D01*
Y34700D01*
X436106Y34694D01*
Y34506D01*
G01X345900Y161700D02*
X342700Y158500D01*
X341184D01*
X339965Y157281D01*
Y153330D01*
X338345Y151710D01*
Y145539D01*
X337206Y144400D01*
X323800D01*
X322000Y142600D01*
Y138000D01*
X318896Y134896D01*
Y128104D01*
X321900Y125100D01*
Y121007D01*
X320585Y119692D01*
Y115035D01*
X322430Y113190D01*
Y111470D01*
X320650Y109690D01*
Y100059D01*
X320945Y99764D01*
Y90639D01*
X319325Y89019D01*
Y85634D01*
X336563Y68396D01*
Y67137D01*
X340475Y63225D01*
X373111D01*
X374675Y64789D01*
X418844D01*
X434325Y49308D01*
Y19683D01*
X444108Y9900D01*
X446800D01*
G01X336900Y161600D02*
X337900D01*
X339500Y160000D01*
Y157877D01*
X338623Y157000D01*
X337400D01*
X336996Y156596D01*
Y152750D01*
X336596Y152350D01*
X327100D01*
X326700Y151950D01*
Y151150D01*
X326350Y150800D01*
X325650D01*
X325300Y151150D01*
Y151875D01*
X324950Y152225D01*
X324250D01*
X323900Y151875D01*
Y150035D01*
X323465Y149600D01*
X322900D01*
X322500Y150000D01*
Y151875D01*
X322150Y152225D01*
X321300D01*
X320900Y151825D01*
Y148300D01*
X320500Y147900D01*
X314961D01*
X314324Y147263D01*
Y146676D01*
X314774Y146226D01*
X321474D01*
X322000Y145700D01*
Y144800D01*
X321600Y144400D01*
X318900D01*
X318500Y144000D01*
Y142900D01*
X318900Y142500D01*
X320277D01*
X320677Y142100D01*
Y139900D01*
X320277Y139500D01*
X318446D01*
X317500Y138554D01*
Y137000D01*
X318046Y136454D01*
Y130546D01*
X317000Y129500D01*
Y128100D01*
X321100Y124000D01*
Y122300D01*
X320100Y121300D01*
X318900D01*
X317050Y119450D01*
Y118121D01*
X318500Y116671D01*
Y115829D01*
X317520Y114849D01*
Y112492D01*
X317964Y112046D01*
X318900Y111110D01*
Y109900D01*
X318500Y109500D01*
Y108400D01*
X318900Y108000D01*
Y105500D01*
X317500Y104100D01*
Y102936D01*
X318336Y102100D01*
X319050D01*
X319500Y101650D01*
Y98450D01*
X319050Y98000D01*
X318900D01*
G01X317600Y93625D02*
X316475Y92500D01*
X315175D01*
X314725Y92950D01*
Y94725D01*
X317375Y97375D01*
Y102000D01*
X315500Y103875D01*
Y105000D01*
X316000Y105500D01*
X317000D01*
X317500Y106000D01*
Y108000D01*
X316475Y109025D01*
X314525D01*
X313500Y110050D01*
Y111550D01*
X316500Y114550D01*
Y116547D01*
X315000Y118047D01*
Y119100D01*
X317700Y121800D01*
Y125000D01*
X315700Y127000D01*
X313500D01*
X313000Y127500D01*
Y128650D01*
X313850Y129500D01*
X315000D01*
X316398Y130898D01*
Y135898D01*
X313061Y139235D01*
Y143050D01*
X313511Y143500D01*
X314711D01*
X315161Y143050D01*
Y139950D01*
X315611Y139500D01*
X316811D01*
X317261Y139950D01*
Y145126D01*
X316911Y145476D01*
X313411D01*
X313061Y145826D01*
Y147061D01*
X316000Y150000D01*
Y153000D01*
X317000Y154000D01*
Y155500D01*
X316000Y156500D01*
Y158000D01*
X317000Y159000D01*
X317500D01*
X320200Y156300D01*
X325300D01*
X326000Y157000D01*
Y158500D01*
X327000Y159500D01*
X328000D01*
X328500Y159000D01*
Y157300D01*
X329500Y156300D01*
X334700D01*
X335499Y155501D01*
Y153846D01*
G01X331200Y88600D02*
X329425Y90375D01*
Y93291D01*
X328591Y94125D01*
X326875D01*
X325500Y95500D01*
Y97923D01*
X327725Y100148D01*
Y101102D01*
X327990Y101367D01*
Y120514D01*
X328000Y120524D01*
Y121678D01*
X327883Y121795D01*
Y122826D01*
X327597Y123112D01*
Y126113D01*
X328431Y126947D01*
X330047D01*
X336900Y133800D01*
Y137590D01*
X336939Y137629D01*
Y139039D01*
X338320Y140420D01*
Y141300D01*
G01X329300Y87300D02*
X328231D01*
X324545Y90986D01*
Y92991D01*
X324500Y93036D01*
Y97984D01*
X326506Y99990D01*
Y101222D01*
X325500Y102228D01*
Y110484D01*
X326725Y111709D01*
Y113859D01*
X326775Y113909D01*
Y115091D01*
X324888Y116978D01*
Y122971D01*
X326843Y124926D01*
Y127940D01*
X326000Y128783D01*
Y131160D01*
X326940Y132100D01*
X329381D01*
X335501Y138220D01*
X335514D01*
G01X327577Y48475D02*
X328789D01*
X333414Y53100D01*
X347840D01*
X350364Y50576D01*
X355836D01*
X359135Y53875D01*
X376989D01*
X378553Y55439D01*
X414966D01*
X424775Y45630D01*
Y39628D01*
X422761Y37614D01*
Y17624D01*
X423500Y16885D01*
G01X356900Y186100D02*
Y170200D01*
X353875Y167175D01*
Y146510D01*
X346216Y138851D01*
Y133916D01*
X341100Y128800D01*
Y127184D01*
X335125Y121209D01*
Y99825D01*
X333425Y98125D01*
Y81677D01*
X348777Y66325D01*
X371825D01*
X373389Y67889D01*
X420130D01*
X437881Y50138D01*
Y27941D01*
X436240Y26300D01*
G01X330900Y93400D02*
X328900Y95400D01*
X327300D01*
X326575Y96125D01*
Y97937D01*
X328475Y99837D01*
Y100791D01*
X329045Y101361D01*
Y116045D01*
X330840Y117840D01*
Y123000D01*
X332880Y125040D01*
Y126590D01*
X332552Y126918D01*
Y128269D01*
X336562Y132279D01*
X343279D01*
X344028Y133028D01*
Y137554D01*
X342550Y139032D01*
Y141650D01*
X343103Y142203D01*
Y143503D01*
X344500Y144900D01*
Y150443D01*
X349597Y155540D01*
X350640D01*
X350700Y155600D01*
G01X794032Y27032D02*
X790000Y31064D01*
Y47676D01*
X774344Y63332D01*
X769152D01*
X744484Y88000D01*
X729172D01*
X717700Y99472D01*
Y137811D01*
X702836Y152675D01*
X658025D01*
X657495Y153205D01*
X648055D01*
X615360Y185900D01*
X609900D01*
X607500Y188300D01*
G01X631900Y175850D02*
Y177800D01*
X633775Y179675D01*
X635398D01*
X644373Y170700D01*
X664900D01*
X679225Y156375D01*
X704370D01*
X721400Y139345D01*
Y108689D01*
X733589Y96500D01*
X741218D01*
X770686Y67032D01*
X794032D01*
G01X640461Y181410D02*
X624525Y197346D01*
Y198986D01*
X643539Y218000D01*
X736938D01*
X738463Y219525D01*
X741725D01*
X744100Y221900D01*
G01X629700Y198300D02*
X647950Y216550D01*
X737539D01*
X739064Y218075D01*
X740725D01*
X742900Y215900D01*
X743800D01*
G01X633100Y198300D02*
X649900Y215100D01*
X738600D01*
X739800Y216300D01*
G01X634748Y177708D02*
Y173841D01*
X651489Y157100D01*
X656217D01*
X658792Y154525D01*
X703603D01*
X719550Y138578D01*
Y100239D01*
X726789Y93000D01*
X742101D01*
X745300Y89800D01*
X745301D01*
X769919Y65182D01*
X775882D01*
X794032Y47032D01*
G01X636500Y198300D02*
Y189889D01*
X650489Y175900D01*
X662317D01*
X673442Y164775D01*
X712014D01*
X723250Y153539D01*
Y117089D01*
X769364Y70975D01*
X795287D01*
X797707Y68555D01*
Y60707D01*
X794032Y57032D01*
G01X646000Y186400D02*
X659000D01*
X678775Y166625D01*
X712781D01*
X725100Y154306D01*
Y117856D01*
X769265Y73691D01*
X795188D01*
X800357Y68522D01*
Y55509D01*
X804032Y51834D01*
Y47032D01*
G01X654851Y191978D02*
Y193462D01*
X674939Y213550D01*
X739150D01*
X739900Y212800D01*
G01X657722Y193800D02*
Y192216D01*
X681463Y168475D01*
X713548D01*
X730775Y151248D01*
Y127925D01*
X734500Y124200D01*
Y111073D01*
X769873Y75700D01*
X800562D01*
X807707Y68555D01*
Y40707D01*
X804032Y37032D01*
G01X673100Y179455D02*
X670521Y189337D01*
X670167Y191287D01*
X668732Y204555D01*
G01X673044Y190456D02*
X694563Y211975D01*
X734625D01*
X735600Y211000D01*
X743000D01*
G01X774500Y31307D02*
Y52300D01*
X742500Y84300D01*
X720799D01*
X712150Y92949D01*
Y101850D01*
X699241Y114759D01*
G01X778000Y31307D02*
Y51867D01*
X743717Y86150D01*
X721566D01*
X714000Y93716D01*
Y103100D01*
X699100Y118000D01*
Y118019D01*
X698970Y118149D01*
G54D14*
X794032Y27032D03*
X804032Y37032D03*
Y47032D03*
X794032D03*
Y57032D03*
Y67032D03*
G54D24*
G01X339405Y226480D02*
X337300Y228585D01*
Y232039D01*
X327789Y241550D01*
X274386D01*
X258061Y225225D01*
X243805D01*
X216155Y197575D01*
X214054D01*
X209825Y193346D01*
Y185550D01*
X205775Y181500D01*
X200500D01*
X195778Y176778D01*
Y161921D01*
X191157Y157300D01*
X171300D01*
X128800Y114800D01*
Y102504D01*
X125170Y98874D01*
Y95113D01*
X99600Y69543D01*
Y61239D01*
X91500Y53139D01*
Y47929D01*
X88771Y45200D01*
X79232D01*
X77571Y43539D01*
Y41517D01*
X76411Y40357D01*
G01X80031D02*
X78871Y41517D01*
Y43000D01*
X79771Y43900D01*
X89310D01*
X92800Y47390D01*
Y52600D01*
X100900Y60700D01*
Y69004D01*
X126470Y94574D01*
Y98335D01*
X130100Y101965D01*
Y114261D01*
X171839Y156000D01*
X191696D01*
X197078Y161382D01*
Y176239D01*
X201039Y180200D01*
X206314D01*
X211125Y185011D01*
Y192807D01*
X214593Y196275D01*
X216694D01*
X244344Y223925D01*
X258600D01*
X274925Y240250D01*
X327250D01*
X336000Y231500D01*
Y228046D01*
X338486Y225560D01*
G01X334013Y225387D02*
X323450Y235950D01*
X274390D01*
X259915Y221475D01*
X245364D01*
X213575Y189686D01*
Y183996D01*
X205000Y175421D01*
Y160339D01*
X202161Y157500D01*
X196661D01*
X192661Y153500D01*
X172804D01*
X132600Y113296D01*
Y101000D01*
X128921Y97321D01*
Y93560D01*
X105400Y70039D01*
Y60100D01*
X106300Y59200D01*
Y53900D01*
X105230Y52830D01*
Y47419D01*
X103861Y46050D01*
X95911D01*
X93218Y43357D01*
Y41416D01*
X92159Y40357D01*
G01X331368Y223871D02*
X323139Y232100D01*
X275844D01*
X260944Y217200D01*
X246393D01*
X235807Y206614D01*
Y204893D01*
X232839Y201925D01*
X231150D01*
X217325Y188100D01*
Y180710D01*
X208750Y172135D01*
Y158364D01*
X201386Y151000D01*
X198820D01*
X190870Y143050D01*
X184146D01*
X182196Y141100D01*
X174461D01*
X153300Y119939D01*
Y110939D01*
X147113Y104752D01*
Y94232D01*
X116781Y63900D01*
X113561D01*
X111600Y61939D01*
Y52439D01*
X109067Y49906D01*
Y41517D01*
X107907Y40357D01*
G01X333093Y224468D02*
X322911Y234650D01*
X274929D01*
X260454Y220175D01*
X245903D01*
X214875Y189147D01*
Y183457D01*
X206300Y174882D01*
Y159800D01*
X202700Y156200D01*
X197200D01*
X193200Y152200D01*
X173343D01*
X133900Y112757D01*
Y100461D01*
X130221Y96782D01*
Y93021D01*
X106700Y69500D01*
Y60639D01*
X107600Y59739D01*
Y53361D01*
X106530Y52291D01*
Y46880D01*
X104400Y44750D01*
X96450D01*
X94518Y42818D01*
Y41618D01*
X95779Y40357D01*
G01X327207Y223979D02*
X322836Y228350D01*
X283579D01*
X275429Y220200D01*
X271782D01*
X265032Y213450D01*
X260150D01*
X257900Y211200D01*
X247418D01*
X234393Y198175D01*
X232704D01*
X221075Y186546D01*
Y179156D01*
X215802Y173883D01*
Y156843D01*
X206209Y147250D01*
X200374D01*
X192424Y139300D01*
X185700D01*
X179900Y133500D01*
Y126776D01*
X160800Y107676D01*
Y95489D01*
X153711Y88400D01*
X151901D01*
X129601Y66100D01*
X128155D01*
X124815Y62760D01*
Y41517D01*
X123655Y40357D01*
G01X330449Y222951D02*
X322600Y230800D01*
X276383D01*
X261483Y215900D01*
X246932D01*
X237107Y206075D01*
Y204354D01*
X233378Y200625D01*
X231689D01*
X218625Y187561D01*
Y180171D01*
X210050Y171596D01*
Y157825D01*
X201925Y149700D01*
X199359D01*
X191409Y141750D01*
X184685D01*
X182735Y139800D01*
X175000D01*
X154600Y119400D01*
Y110400D01*
X148413Y104213D01*
Y93693D01*
X117320Y62600D01*
X114100D01*
X112900Y61400D01*
Y51900D01*
X110367Y49367D01*
Y47445D01*
X111207Y46605D01*
Y45255D01*
X110367Y44415D01*
Y41517D01*
X111527Y40357D01*
G01X320300Y221400D02*
X291861D01*
X274361Y203900D01*
X265065D01*
X264190Y203025D01*
X256766D01*
X242841Y189100D01*
X236573D01*
X230225Y182752D01*
Y177060D01*
X223752Y170587D01*
Y153547D01*
X220127Y149922D01*
Y148197D01*
X212425Y140495D01*
Y134264D01*
X209461Y131300D01*
X196961D01*
X176475Y110814D01*
Y105014D01*
X168880Y97419D01*
Y88420D01*
X148650Y68190D01*
Y67058D01*
X146048Y64456D01*
X144774D01*
X141750Y61432D01*
Y57579D01*
X140563Y56392D01*
Y41517D01*
X139403Y40357D01*
G01X326287Y223059D02*
X322296Y227050D01*
X284118D01*
X275968Y218900D01*
X272321D01*
X265571Y212150D01*
X260689D01*
X258439Y209900D01*
X247957D01*
X234932Y196875D01*
X233243D01*
X222375Y186007D01*
Y178617D01*
X217102Y173344D01*
Y156304D01*
X206748Y145950D01*
X200913D01*
X192963Y138000D01*
X186239D01*
X181200Y132961D01*
Y126237D01*
X162100Y107137D01*
Y94950D01*
X154250Y87100D01*
X152440D01*
X130140Y64800D01*
X128694D01*
X126115Y62221D01*
Y41517D01*
X127275Y40357D01*
G01X320300Y220100D02*
X292400D01*
X274900Y202600D01*
X265604D01*
X264729Y201725D01*
X257305D01*
X243380Y187800D01*
X237112D01*
X231525Y182213D01*
Y176521D01*
X225052Y170048D01*
Y153008D01*
X221427Y149383D01*
Y147658D01*
X213725Y139956D01*
Y133725D01*
X210000Y130000D01*
X197500D01*
X177775Y110275D01*
Y104475D01*
X170180Y96880D01*
Y87881D01*
X149950Y67651D01*
Y66519D01*
X146587Y63156D01*
X145313D01*
X143050Y60893D01*
Y57040D01*
X141863Y55853D01*
Y41517D01*
X143023Y40357D01*
G01X313786Y217339D02*
X306197Y209750D01*
X285515D01*
X275915Y200150D01*
X266619D01*
X265744Y199275D01*
X258320D01*
X249842Y190797D01*
Y186788D01*
X240721Y177667D01*
Y171309D01*
X232000Y162588D01*
Y150239D01*
X219375Y137614D01*
Y127214D01*
X211430Y119269D01*
Y112930D01*
X209300Y110800D01*
X206800D01*
X198000Y102000D01*
Y93000D01*
X188900Y83900D01*
Y73139D01*
X185400Y69639D01*
Y67739D01*
X176911Y59250D01*
X162511D01*
X155641Y52380D01*
X154080D01*
X152100Y50400D01*
Y46900D01*
X156311Y42689D01*
Y41517D01*
X155151Y40357D01*
G01X314706Y216420D02*
X313751Y215465D01*
Y214277D01*
X312797Y213323D01*
X311609D01*
X306736Y208450D01*
X286054D01*
X276454Y198850D01*
X267158D01*
X266283Y197975D01*
X258859D01*
X251142Y190258D01*
Y186249D01*
X242021Y177128D01*
Y170770D01*
X233300Y162049D01*
Y149700D01*
X220675Y137075D01*
Y126675D01*
X212730Y118730D01*
Y112391D01*
X209839Y109500D01*
X207339D01*
X199300Y101461D01*
Y92461D01*
X190200Y83361D01*
Y72600D01*
X186700Y69100D01*
Y67200D01*
X177450Y57950D01*
X163050D01*
X156180Y51080D01*
X154619D01*
X153400Y49861D01*
Y47439D01*
X157611Y43228D01*
Y41517D01*
X158771Y40357D01*
G01X305500Y206350D02*
X303511D01*
X302461Y205300D01*
X286369D01*
X277469Y196400D01*
X268173D01*
X267298Y195525D01*
X259874D01*
X255125Y190776D01*
Y186767D01*
X244471Y176113D01*
Y169755D01*
X235900Y161184D01*
Y146100D01*
X237444Y144556D01*
Y133554D01*
X219350Y115460D01*
Y109850D01*
X207700Y98200D01*
Y69100D01*
X212750Y64050D01*
Y55339D01*
X207511Y50100D01*
X188800D01*
X184778Y46078D01*
X174838D01*
X172059Y43299D01*
Y41517D01*
X170899Y40357D01*
G01X316100Y201118D02*
X287491D01*
X279023Y192650D01*
X269727D01*
X256677Y179600D01*
X253266D01*
X249800Y176134D01*
Y169780D01*
X239650Y159630D01*
Y147655D01*
X241194Y146111D01*
Y139661D01*
X243208Y137647D01*
Y135147D01*
X241194Y133133D01*
Y129406D01*
X241193Y129405D01*
Y128866D01*
X241195D01*
X243208Y126853D01*
Y126100D01*
X242408Y125300D01*
X240639D01*
X238639Y127300D01*
X236494D01*
X234881Y125687D01*
Y123973D01*
X239191Y119664D01*
Y119030D01*
X237914Y117753D01*
X237280D01*
X232970Y122062D01*
X231256D01*
X229221Y120027D01*
Y118313D01*
X233531Y114004D01*
Y113370D01*
X232254Y112093D01*
X231620D01*
X227310Y116402D01*
X225596D01*
X223100Y113906D01*
Y107600D01*
X218500Y103000D01*
Y68039D01*
X216600Y66139D01*
Y51265D01*
X218532Y49332D01*
X219672Y48194D01*
Y48192D01*
X221500Y46366D01*
Y45139D01*
X218361Y42000D01*
X215100D01*
X214200Y42900D01*
Y44700D01*
X212550Y46350D01*
X206650D01*
X204646Y44346D01*
X189146D01*
X187700Y42900D01*
Y41410D01*
X186647Y40357D01*
G01X305500Y205050D02*
X304050D01*
X303000Y204000D01*
X286908D01*
X278008Y195100D01*
X268712D01*
X267837Y194225D01*
X260413D01*
X256425Y190237D01*
Y186228D01*
X245771Y175574D01*
Y169216D01*
X237200Y160645D01*
Y146639D01*
X238744Y145095D01*
Y133015D01*
X220650Y114921D01*
Y109311D01*
X209000Y97661D01*
Y69639D01*
X214050Y64589D01*
Y54800D01*
X208050Y48800D01*
X189339D01*
X185317Y44778D01*
X182868D01*
X182028Y43938D01*
X180678D01*
X179838Y44778D01*
X175377D01*
X173359Y42760D01*
Y41517D01*
X174519Y40357D01*
G01X316100Y199818D02*
X288030D01*
X279562Y191350D01*
X270266D01*
X257216Y178300D01*
X253805D01*
X251100Y175595D01*
Y169241D01*
X240950Y159091D01*
Y148194D01*
X242494Y146650D01*
Y140200D01*
X244508Y138186D01*
Y134608D01*
X242494Y132594D01*
Y129406D01*
X244508Y127392D01*
Y125561D01*
X242947Y124000D01*
X240100D01*
X238100Y126000D01*
X237033D01*
X236181Y125148D01*
Y124512D01*
X240491Y120203D01*
Y118491D01*
X238453Y116453D01*
X236741D01*
X232431Y120762D01*
X231795D01*
X230521Y119488D01*
Y118852D01*
X234831Y114543D01*
Y112831D01*
X232793Y110793D01*
X231081D01*
X226771Y115102D01*
X226135D01*
X224400Y113367D01*
Y107061D01*
X219800Y102461D01*
Y67500D01*
X217900Y65600D01*
Y51804D01*
X222800Y46905D01*
Y44600D01*
X218900Y40700D01*
X214561D01*
X212900Y42361D01*
Y44161D01*
X212011Y45050D01*
X207189D01*
X205185Y43046D01*
X189685D01*
X189000Y42361D01*
Y41624D01*
X190267Y40357D01*
G01X199441Y187547D02*
X198266Y188722D01*
X194939D01*
X192275Y191386D01*
Y194414D01*
X196161Y198300D01*
X204961D01*
X220336Y213675D01*
X225034D01*
X240334Y228975D01*
X256408D01*
X272883Y245450D01*
X353339D01*
X368489Y230300D01*
X372461D01*
X376200Y234039D01*
Y239549D01*
X379651Y243000D01*
X390839D01*
X392711Y241128D01*
X394229D01*
G01X391788Y238760D02*
Y240212D01*
X390300Y241700D01*
X388950D01*
X388110Y240860D01*
X386760D01*
X385920Y241700D01*
X384570D01*
X383730Y240860D01*
X382380D01*
X381540Y241700D01*
X380190D01*
X377500Y239010D01*
Y233500D01*
X373000Y229000D01*
X367950D01*
X352800Y244150D01*
X273422D01*
X256947Y227675D01*
X240873D01*
X230518Y217320D01*
Y216132D01*
X229563Y215177D01*
X228375D01*
X225573Y212375D01*
X220875D01*
X219920Y211420D01*
Y210232D01*
X218966Y209278D01*
X217778D01*
X205500Y197000D01*
X196700D01*
X193575Y193875D01*
Y191925D01*
X195478Y190022D01*
X198467D01*
X199392Y190947D01*
G01X315800Y197270D02*
X314450D01*
X313610Y196430D01*
X312260D01*
X311420Y197270D01*
X301670D01*
X299900Y195500D01*
X295397D01*
X290450Y190553D01*
Y179900D01*
X279600Y169050D01*
X268046D01*
X258200Y159204D01*
Y133061D01*
X256108Y130969D01*
Y89731D01*
X259000Y86839D01*
Y72100D01*
X248725Y61825D01*
X246743D01*
X245675Y60757D01*
Y58564D01*
X255139Y49100D01*
X256750D01*
X257590Y49940D01*
X258940D01*
X259780Y49100D01*
X262139D01*
X263094Y48145D01*
X264282D01*
X265236Y47191D01*
Y46003D01*
X267800Y43439D01*
Y41600D01*
X268910Y40490D01*
G01X315800Y198570D02*
X301131D01*
X299361Y196800D01*
X294858D01*
X289150Y191092D01*
Y180439D01*
X279061Y170350D01*
X267507D01*
X256900Y159743D01*
Y133600D01*
X254808Y131508D01*
Y89192D01*
X257700Y86300D01*
Y72639D01*
X248186Y63125D01*
X246204D01*
X244375Y61296D01*
Y58025D01*
X254600Y47800D01*
X261600D01*
X266500Y42900D01*
Y41850D01*
X265140Y40490D01*
G01X316844Y196010D02*
Y195013D01*
X315681Y193850D01*
X297212D01*
X292950Y189588D01*
Y175358D01*
X284192Y166600D01*
X269061D01*
X260650Y158189D01*
Y127750D01*
X259600Y126700D01*
Y107100D01*
X269850Y96850D01*
Y95050D01*
X266900Y92100D01*
X263600D01*
X261500Y90000D01*
Y85900D01*
X263800Y83600D01*
X267850D01*
X269850Y81600D01*
Y70350D01*
X273400Y66800D01*
X277975D01*
X280775Y64000D01*
Y54511D01*
X282223Y53063D01*
Y41725D01*
X280988Y40490D01*
G01X319801Y194890D02*
X318560D01*
X316220Y192550D01*
X297751D01*
X294250Y189049D01*
Y174819D01*
X284731Y165300D01*
X269600D01*
X261950Y157650D01*
Y156410D01*
X262790Y155570D01*
Y154220D01*
X261950Y153380D01*
Y152030D01*
X262790Y151190D01*
Y149840D01*
X261950Y149000D01*
Y147650D01*
X262790Y146810D01*
Y145460D01*
X261950Y144620D01*
Y127211D01*
X260900Y126161D01*
Y107639D01*
X271150Y97389D01*
Y94511D01*
X267439Y90800D01*
X264139D01*
X262800Y89461D01*
Y86439D01*
X264339Y84900D01*
X268389D01*
X271150Y82139D01*
Y70889D01*
X273939Y68100D01*
X278514D01*
X282075Y64539D01*
Y55050D01*
X283523Y53602D01*
Y41725D01*
X284758Y40490D01*
G01X301300Y188700D02*
X301000Y188400D01*
X299621D01*
X295750Y184529D01*
Y172854D01*
X286500Y163604D01*
Y143021D01*
X281901Y138422D01*
X280713D01*
X279759Y137468D01*
Y136280D01*
X278804Y135325D01*
X277616D01*
X276662Y134371D01*
Y133183D01*
X274775Y131296D01*
Y123075D01*
X273935Y122235D01*
Y120885D01*
X274775Y120045D01*
Y118695D01*
X273935Y117855D01*
Y116505D01*
X274775Y115665D01*
Y113186D01*
X277761Y110200D01*
X279661D01*
X280385Y109476D01*
Y106285D01*
X279300Y105200D01*
X276800D01*
X274775Y103175D01*
Y94725D01*
X277000Y92500D01*
X279800D01*
X281925Y90375D01*
Y87700D01*
X279925Y85700D01*
X277500D01*
X276000Y84200D01*
Y81300D01*
X277349Y79950D01*
X277350D01*
X277730Y79570D01*
X280591D01*
X282300Y77861D01*
Y72105D01*
X284605Y69800D01*
Y66495D01*
X288200Y62900D01*
X293661D01*
X294350Y62211D01*
Y56350D01*
X292619Y54619D01*
Y48581D01*
X297971Y43229D01*
Y41725D01*
X296736Y40490D01*
G01X303480Y189100D02*
Y188740D01*
X301840Y187100D01*
X300160D01*
X297050Y183990D01*
Y172315D01*
X287800Y163065D01*
Y142482D01*
X276075Y130757D01*
Y113725D01*
X278300Y111500D01*
X280200D01*
X281685Y110015D01*
Y105746D01*
X279839Y103900D01*
X277339D01*
X276075Y102636D01*
Y95264D01*
X277539Y93800D01*
X280339D01*
X283225Y90914D01*
Y87161D01*
X280464Y84400D01*
X278039D01*
X277300Y83661D01*
Y81839D01*
X278269Y80870D01*
X281130D01*
X283600Y78400D01*
Y72644D01*
X285905Y70339D01*
Y67034D01*
X288739Y64200D01*
X294200D01*
X295650Y62750D01*
Y55811D01*
X293919Y54080D01*
Y49120D01*
X299271Y43768D01*
Y41725D01*
X300506Y40490D01*
G01X307500Y188000D02*
X307800Y187700D01*
Y186239D01*
X306563Y185002D01*
X300813D01*
X298750Y182939D01*
Y170550D01*
X290250Y162050D01*
Y139893D01*
X288650Y138293D01*
Y129250D01*
X286500Y127100D01*
X282800D01*
X281300Y125600D01*
Y123600D01*
X282900Y122000D01*
X287350D01*
X288650Y120700D01*
Y118850D01*
X284975Y115175D01*
Y108264D01*
X284135Y107424D01*
Y106074D01*
X284975Y105234D01*
Y103884D01*
X284135Y103044D01*
Y101694D01*
X284975Y100854D01*
Y92725D01*
X286550Y91150D01*
Y84750D01*
X288547Y82753D01*
Y81136D01*
X286550Y79139D01*
Y76250D01*
X288500Y74300D01*
X290639D01*
X293439Y77100D01*
X294295D01*
X299295Y72100D01*
X305960D01*
X312080Y65978D01*
Y63539D01*
X310741Y62200D01*
X308440D01*
X305639Y65000D01*
X301561D01*
X298700Y62139D01*
Y52661D01*
X308061Y43300D01*
X313200D01*
X313700Y42800D01*
Y41906D01*
X312484Y40690D01*
G01X322300Y178350D02*
X320911D01*
X311361Y168800D01*
X305161D01*
X299040Y162679D01*
Y153109D01*
X294000Y148069D01*
Y138339D01*
X292400Y136739D01*
Y108039D01*
X290500Y106139D01*
Y86200D01*
X300450Y76250D01*
X307250D01*
X325000Y58500D01*
Y55900D01*
X324000Y54900D01*
G01X322300Y177050D02*
X321450D01*
X320495Y176095D01*
Y174907D01*
X319541Y173953D01*
X318353D01*
X317398Y172998D01*
Y171810D01*
X316444Y170856D01*
X315256D01*
X311900Y167500D01*
X305700D01*
X300340Y162140D01*
Y152570D01*
X295300Y147530D01*
Y137800D01*
X293700Y136200D01*
Y107500D01*
X291800Y105600D01*
Y86739D01*
X300989Y77550D01*
X307789D01*
X326300Y59039D01*
Y56000D01*
X327400Y54900D01*
G01X309700Y187997D02*
X309100Y187397D01*
Y185700D01*
X307102Y183702D01*
X301352D01*
X300050Y182400D01*
Y170011D01*
X291550Y161511D01*
Y139354D01*
X289950Y137754D01*
Y128711D01*
X287039Y125800D01*
X283339D01*
X282600Y125061D01*
Y124139D01*
X283439Y123300D01*
X287889D01*
X289950Y121239D01*
Y118311D01*
X286275Y114636D01*
Y93264D01*
X287850Y91689D01*
Y85289D01*
X289847Y83292D01*
Y80597D01*
X287850Y78600D01*
Y76789D01*
X289039Y75600D01*
X290100D01*
X292900Y78400D01*
X294834D01*
X299834Y73400D01*
X306500D01*
X306880Y73020D01*
X306879D01*
X313380Y66517D01*
Y63000D01*
X311280Y60900D01*
X307901D01*
X305100Y63700D01*
X302100D01*
X300000Y61600D01*
Y53200D01*
X308600Y44600D01*
X313739D01*
X315000Y43339D01*
Y41944D01*
X316254Y40690D01*
G54D15*
X799000Y121500D03*
Y125500D03*
X800400Y158500D03*
X799900Y168800D03*
G54D25*
G01X392700Y193563D02*
Y196300D01*
X394294Y197894D01*
Y198954D01*
X393190Y200058D01*
Y201490D01*
X394410Y202710D01*
X395842D01*
X396946Y201606D01*
X398006D01*
X399598Y203198D01*
Y204258D01*
X398958Y204898D01*
Y205958D01*
X400550Y207550D01*
X401610D01*
X402250Y206910D01*
X403310D01*
X406300Y209900D01*
Y230800D01*
X413700Y238200D01*
X475840D01*
X478640Y241000D01*
X582373D01*
X585800Y244427D01*
Y251396D01*
X585767Y251429D01*
Y267200D01*
X586367Y267800D01*
X587800D01*
X588400Y267200D01*
Y265239D01*
X589000Y264639D01*
X590439D01*
X590633Y264833D01*
X590700D01*
G01X590837Y259889D02*
Y258200D01*
X591437Y257600D01*
X592617D01*
X593217Y257000D01*
Y250900D01*
X592617Y250300D01*
X588409D01*
X587809Y249700D01*
Y244809D01*
X582800Y239800D01*
X570300D01*
X569050Y238550D01*
X479655D01*
X476855Y235750D01*
X414715D01*
X410300Y231335D01*
Y210870D01*
X407865Y208435D01*
G01X413800Y221300D02*
Y225000D01*
X415300Y226500D01*
Y227800D01*
X413800Y229300D01*
Y231800D01*
X415300Y233300D01*
X417200D01*
X418500Y232000D01*
X420800D01*
X422100Y233300D01*
X469965D01*
X471040Y232225D01*
X476795D01*
X479470Y234900D01*
X509700D01*
X512075Y232525D01*
X520271D01*
X523846Y236100D01*
X540048D01*
X540723Y236775D01*
X542277D01*
X542952Y236100D01*
X555909D01*
X556500Y236691D01*
X569461D01*
X571270Y238500D01*
X583246D01*
X589123Y244377D01*
Y247223D01*
X590900Y249000D01*
X593100D01*
X594600Y250500D01*
Y257356D01*
X592812Y259144D01*
Y261470D01*
X592462Y261820D01*
Y263632D01*
X594030Y265200D01*
X594500D01*
G01X594600Y260000D02*
Y259300D01*
X596000Y257900D01*
Y249627D01*
X593773Y247400D01*
X591300D01*
X590386Y246486D01*
Y244013D01*
X583623Y237250D01*
X573485D01*
X570476Y234241D01*
X558347D01*
X556956Y232850D01*
X524061D01*
X521286Y230075D01*
X511060D01*
X508685Y232450D01*
X480485D01*
X477810Y229775D01*
X470025D01*
X468950Y230850D01*
X420450D01*
X417800Y228200D01*
Y217400D01*
G01X432509Y90209D02*
X448218Y74500D01*
X485126D01*
X486016Y73610D01*
X488266D01*
X489156Y74500D01*
X494945D01*
X495835Y73610D01*
X498085D01*
X498975Y74500D01*
X501225D01*
X502115Y73610D01*
X504365D01*
X505255Y74500D01*
X507505D01*
X508395Y73610D01*
X510645D01*
X511535Y74500D01*
X515495D01*
X516385Y73610D01*
X518635D01*
X519525Y74500D01*
X521775D01*
X522665Y73610D01*
X524915D01*
X525805Y74500D01*
X528055D01*
X528945Y73610D01*
X531195D01*
X532085Y74500D01*
X542526D01*
X543416Y73610D01*
X545666D01*
X546556Y74500D01*
X548806D01*
X549696Y73610D01*
X551946D01*
X552836Y74500D01*
X555086D01*
X555976Y73610D01*
X558226D01*
X559116Y74500D01*
X561366D01*
X565050Y70816D01*
Y60941D01*
X566616Y59375D01*
X570734D01*
X572450Y61091D01*
Y71100D01*
X573050Y71700D01*
X574850D01*
X575450Y71100D01*
Y61091D01*
X577166Y59375D01*
X580034D01*
X581750Y61091D01*
Y70900D01*
X582350Y71500D01*
X584150D01*
X584750Y70900D01*
Y61091D01*
X586466Y59375D01*
X613367D01*
X628690Y44052D01*
Y42793D01*
X630281Y41202D01*
X631540D01*
X633992Y38750D01*
X640823D01*
X643825Y35748D01*
Y33515D01*
X643700Y33390D01*
Y33290D01*
G01X433676Y91376D02*
X448902Y76150D01*
X562050D01*
X566700Y71500D01*
Y61625D01*
X567300Y61025D01*
X570050D01*
X570800Y61775D01*
Y71784D01*
X572366Y73350D01*
X575534D01*
X577100Y71784D01*
Y61775D01*
X577850Y61025D01*
X579350D01*
X580100Y61775D01*
Y71584D01*
X581666Y73150D01*
X584834D01*
X586400Y71584D01*
Y61775D01*
X587150Y61025D01*
X614051D01*
X634676Y40400D01*
X641507D01*
X645475Y36432D01*
Y31682D01*
X644100Y30307D01*
G01X647000Y29607D02*
X646625Y29982D01*
Y39703D01*
X644346Y41982D01*
X637491D01*
X635350Y44123D01*
Y50116D01*
X634516Y50950D01*
X628016D01*
X615016Y63950D01*
X601466D01*
X599750Y65666D01*
Y74900D01*
X599150Y75500D01*
X597350D01*
X596750Y74900D01*
Y65666D01*
X595034Y63950D01*
X590916D01*
X589350Y65516D01*
Y77316D01*
X587766Y78900D01*
X572956D01*
X572066Y78010D01*
X569816D01*
X568926Y78900D01*
X450266D01*
X432628Y96538D01*
G01X611706Y259387D02*
X612093D01*
X614800Y256680D01*
Y249782D01*
X600043Y235025D01*
X598901D01*
X583869Y219993D01*
X582809D01*
X581097Y221705D01*
X580037D01*
X578975Y220643D01*
Y219583D01*
X579800Y218758D01*
Y217600D01*
X579034Y216834D01*
X575164D01*
X573405Y215075D01*
X508991D01*
X506541Y212625D01*
X502125D01*
X501375Y213375D01*
Y214325D01*
X500625Y215075D01*
X499125D01*
X498375Y214325D01*
Y213375D01*
X497625Y212625D01*
X496125D01*
X495375Y213375D01*
Y214325D01*
X494625Y215075D01*
X493125D01*
X492375Y214325D01*
Y213375D01*
X491625Y212625D01*
X490125D01*
X489375Y213375D01*
Y214325D01*
X488625Y215075D01*
X487125D01*
X486375Y214325D01*
Y213375D01*
X485625Y212625D01*
X484125D01*
X483375Y213375D01*
Y214325D01*
X482625Y215075D01*
X481125D01*
X480375Y214325D01*
Y213375D01*
X479625Y212625D01*
X467175D01*
X465175Y214625D01*
X433625D01*
X429000Y210000D01*
G01X611536Y264385D02*
X611465D01*
X608100Y261020D01*
Y260500D01*
X610938Y257662D01*
X611838D01*
X613600Y255900D01*
Y251864D01*
X610630Y248894D01*
X609570D01*
X607962Y250502D01*
X606902D01*
X604780Y248380D01*
Y247320D01*
X606388Y245712D01*
Y244388D01*
X599725Y237725D01*
X597865D01*
X594127Y233987D01*
Y233986D01*
X587508Y227367D01*
X582232D01*
X572390Y217525D01*
X478203D01*
X477453Y216775D01*
Y216209D01*
X476703Y215459D01*
X475203D01*
X474453Y216209D01*
Y216775D01*
X473703Y217525D01*
X472203D01*
X471453Y216775D01*
Y216209D01*
X470703Y215459D01*
X469203D01*
X468453Y216209D01*
Y216775D01*
X467703Y217525D01*
X433725D01*
X428800Y212600D01*
G01X598398Y260199D02*
X598900Y259697D01*
Y248000D01*
X588351Y237451D01*
X587197D01*
X584463Y234717D01*
X577882D01*
X572506Y229341D01*
X560377D01*
X558161Y227125D01*
X548981D01*
X548231Y226375D01*
X546825D01*
X545325Y227875D01*
X543575D01*
X542075Y226375D01*
X537625D01*
X536125Y227875D01*
X533575D01*
X532075Y226375D01*
X529484D01*
X527984Y227875D01*
X526016D01*
X524751Y226610D01*
Y226609D01*
X523317Y225175D01*
X523316D01*
X523016Y224875D01*
X509330D01*
X508505Y225700D01*
X507152D01*
X506327Y224875D01*
X504415D01*
X503665Y225625D01*
Y226900D01*
X503015Y227550D01*
X501315D01*
X500665Y226900D01*
Y225600D01*
X499940Y224875D01*
X498390D01*
X497665Y225600D01*
Y226900D01*
X497015Y227550D01*
X495315D01*
X494665Y226900D01*
Y225625D01*
X493915Y224875D01*
X492415D01*
X491665Y225625D01*
Y226900D01*
X491015Y227550D01*
X489315D01*
X488665Y226900D01*
Y225625D01*
X487915Y224875D01*
X486415D01*
X485665Y225625D01*
Y227000D01*
X485115Y227550D01*
X483215D01*
X482665Y227000D01*
Y225625D01*
X481915Y224875D01*
X429675D01*
X429300Y224500D01*
G01X424901Y215401D02*
Y216100D01*
X431226Y222425D01*
X528166D01*
X529666Y223925D01*
X533334D01*
X534499Y222760D01*
X536760D01*
X537925Y223925D01*
X539535D01*
X540700Y222760D01*
X542560D01*
X543800Y224000D01*
X545260D01*
X546500Y222760D01*
X548081D01*
X549996Y224675D01*
X562081D01*
X564053Y226647D01*
X573547D01*
X579167Y232267D01*
X585478D01*
X600200Y246989D01*
Y258400D01*
X609110Y267310D01*
X613016D01*
X615537Y264789D01*
G01X427100Y213800D02*
X433275Y219975D01*
X529181D01*
X530681Y221475D01*
X532319D01*
X533484Y220310D01*
X571710D01*
X579782Y228382D01*
Y228383D01*
X581216Y229817D01*
X586493D01*
X591677Y235001D01*
Y235002D01*
X594126Y237451D01*
X594127D01*
X596300Y239624D01*
Y240800D01*
X601350Y245850D01*
Y256710D01*
X602770Y258130D01*
X604230D01*
X605800Y259700D01*
Y261160D01*
X610800Y266160D01*
X612272D01*
X613655Y264777D01*
Y261477D01*
X615243Y259889D01*
X615343D01*
X615532Y259700D01*
G01X598300Y265400D02*
X597300D01*
X596562Y264662D01*
Y259532D01*
X597500Y258594D01*
Y249500D01*
X594200Y246200D01*
X592400D01*
X591550Y245350D01*
Y243550D01*
X584000Y236000D01*
X575700D01*
X571491Y231791D01*
X559362D01*
X557146Y229575D01*
X553725D01*
X552900Y230400D01*
X549900D01*
X549075Y229575D01*
X547090D01*
X546265Y230400D01*
X542635D01*
X541167Y228932D01*
X538534D01*
X537065Y230400D01*
X525076D01*
X522301Y227625D01*
X510045D01*
X507670Y230000D01*
X481500D01*
X478825Y227325D01*
X463535D01*
X462460Y228400D01*
X460535D01*
X459460Y227325D01*
X457010D01*
X455935Y228400D01*
X454010D01*
X452935Y227325D01*
X451010D01*
X449935Y228400D01*
X448010D01*
X446935Y227325D01*
X445010D01*
X443935Y228400D01*
X442010D01*
X440935Y227325D01*
X439010D01*
X437935Y228400D01*
X436010D01*
X434935Y227325D01*
X433010D01*
X431935Y228400D01*
X430010D01*
X428935Y227325D01*
X427010D01*
X425935Y228400D01*
X423100D01*
G01X649550Y30807D02*
X648275Y32082D01*
Y40387D01*
X645030Y43632D01*
X638175D01*
X637000Y44807D01*
Y50800D01*
X635200Y52600D01*
X628700D01*
X615700Y65600D01*
X602150D01*
X601400Y66350D01*
Y75584D01*
X599834Y77150D01*
X596666D01*
X595100Y75584D01*
Y66350D01*
X594350Y65600D01*
X591600D01*
X591000Y66200D01*
Y78000D01*
X588450Y80550D01*
X450950D01*
X433700Y97800D01*
G01X645300Y15507D02*
X644850Y15957D01*
Y18273D01*
X645900Y19323D01*
Y22107D01*
X653325Y29532D01*
Y35732D01*
X651750Y37307D01*
Y45184D01*
X650250Y46684D01*
Y50776D01*
X647750Y53276D01*
Y54150D01*
X642400Y59500D01*
X628176D01*
X616926Y70750D01*
X608184D01*
X607050Y71884D01*
Y80384D01*
X601934Y85500D01*
X491657D01*
X490907Y86250D01*
Y88284D01*
X489341Y89850D01*
X486173D01*
X484607Y88284D01*
Y86250D01*
X483857Y85500D01*
X482357D01*
X481607Y86250D01*
Y87834D01*
X479891Y89550D01*
X477023D01*
X475307Y87834D01*
Y86250D01*
X474557Y85500D01*
X464034D01*
X461634Y87900D01*
X449824D01*
X438225Y99499D01*
Y100100D01*
G01X644193Y12907D02*
X643200Y13900D01*
Y18957D01*
X644250Y20007D01*
Y22791D01*
X652000Y30541D01*
Y34723D01*
X650100Y36623D01*
Y44500D01*
X648600Y46000D01*
Y50092D01*
X646100Y52592D01*
Y53466D01*
X641716Y57850D01*
X627492D01*
X616242Y69100D01*
X607500D01*
X605400Y71200D01*
Y79700D01*
X601250Y83850D01*
X490973D01*
X489257Y85566D01*
Y87600D01*
X488657Y88200D01*
X486857D01*
X486257Y87600D01*
Y85566D01*
X484541Y83850D01*
X481673D01*
X479957Y85566D01*
Y87150D01*
X479207Y87900D01*
X477707D01*
X476957Y87150D01*
Y85566D01*
X475241Y83850D01*
X463350D01*
X460950Y86250D01*
X449140D01*
X436575Y98815D01*
Y100100D01*
G01X648400Y15490D02*
X648550Y15640D01*
Y22991D01*
X654800Y29241D01*
Y42662D01*
X657200Y45062D01*
Y50366D01*
X656016Y51550D01*
X653366D01*
X650500Y54416D01*
Y55466D01*
X643516Y62450D01*
X629116D01*
X617866Y73700D01*
X613316D01*
X609800Y77216D01*
Y81766D01*
X598492Y93074D01*
X586316D01*
X585426Y92184D01*
X583176D01*
X582286Y93074D01*
X509814D01*
X508924Y92184D01*
X506674D01*
X505784Y93074D01*
X472424D01*
X470708Y91358D01*
X466340D01*
X464624Y93074D01*
X461844D01*
X460954Y92184D01*
X458704D01*
X457814Y93074D01*
X455564D01*
X454674Y92184D01*
X452424D01*
X451534Y93074D01*
X448820D01*
X440575Y101319D01*
G01X648800Y12707D02*
X648962D01*
X650200Y13945D01*
Y22307D01*
X656175Y28282D01*
Y41703D01*
X658850Y44378D01*
Y51050D01*
X656700Y53200D01*
X654050D01*
X652150Y55100D01*
Y56150D01*
X644200Y64100D01*
X629800D01*
X618550Y75350D01*
X614000D01*
X611450Y77900D01*
Y82450D01*
X599176Y94724D01*
X471740D01*
X470024Y93008D01*
X467024D01*
X465308Y94724D01*
X461160D01*
X460317Y93881D01*
X459257D01*
X458414Y94724D01*
X449504D01*
X441742Y102486D01*
G01X441550Y205350D02*
X462250D01*
X464775Y202825D01*
X566150D01*
X568225Y204900D01*
X584809D01*
X602479Y222570D01*
X603559D01*
X608175Y227186D01*
Y229890D01*
X614910Y236625D01*
X616043D01*
X617459Y238041D01*
Y241797D01*
X621700Y246038D01*
Y256900D01*
X622932Y258132D01*
Y260188D01*
X622933Y260189D01*
G01X622899Y265189D02*
Y265169D01*
X621155Y263425D01*
Y260827D01*
X621157Y260825D01*
Y258557D01*
X619900Y257300D01*
Y246918D01*
X608806Y235824D01*
Y233986D01*
X605725Y230905D01*
Y228201D01*
X602544Y225020D01*
X601464D01*
X585928Y209484D01*
X578209D01*
X576075Y207350D01*
X567210D01*
X565135Y205275D01*
X543888D01*
X543138Y206025D01*
Y206698D01*
X542388Y207448D01*
X540888D01*
X540138Y206698D01*
Y206025D01*
X539388Y205275D01*
X537888D01*
X537138Y206025D01*
Y206698D01*
X536388Y207448D01*
X534888D01*
X534138Y206698D01*
Y206025D01*
X533388Y205275D01*
X531888D01*
X531138Y206025D01*
Y206698D01*
X530388Y207448D01*
X528888D01*
X528138Y206698D01*
Y206025D01*
X527388Y205275D01*
X464925D01*
X462600Y207600D01*
X441200D01*
X440400Y206800D01*
G01X619100Y265300D02*
Y265120D01*
X617405Y263425D01*
Y260627D01*
X617407Y260625D01*
Y259107D01*
X616400Y258100D01*
Y248700D01*
X600275Y232575D01*
X599916D01*
X581725Y214384D01*
X576179D01*
X574270Y212475D01*
X524654D01*
X523904Y211725D01*
Y210925D01*
X523154Y210175D01*
X521654D01*
X520904Y210925D01*
Y211725D01*
X520154Y212475D01*
X518654D01*
X517904Y211725D01*
Y210925D01*
X517154Y210175D01*
X515654D01*
X514904Y210925D01*
Y211725D01*
X514154Y212475D01*
X509856D01*
X507556Y210175D01*
X466160D01*
X464160Y212175D01*
X434175D01*
G01X438800Y208300D02*
X440000Y209500D01*
X463370D01*
X465145Y207725D01*
X524200D01*
X526500Y210025D01*
X543500D01*
X545799Y207725D01*
X564120D01*
X566420Y210025D01*
X575285D01*
X577194Y211934D01*
X582740D01*
X585981Y215175D01*
X588154D01*
X590300Y217321D01*
Y219494D01*
X592153Y221347D01*
X594326D01*
X596303Y223324D01*
Y225497D01*
X598276Y227470D01*
X600449D01*
X600450Y227471D01*
X601530D01*
X603275Y229216D01*
Y231975D01*
X606356Y235056D01*
Y236016D01*
X618100Y247760D01*
Y257700D01*
X618976Y258576D01*
Y259683D01*
X619382Y260089D01*
G01X638032Y260342D02*
X638030Y260340D01*
Y257712D01*
X637018Y256700D01*
Y251429D01*
X638400Y250047D01*
Y225392D01*
X594408Y181400D01*
X492400D01*
X491100Y180100D01*
X462950D01*
G01X630432Y260100D02*
Y258432D01*
X628500Y256500D01*
Y231841D01*
X591758Y195099D01*
X589236D01*
X589235Y195100D01*
X572285D01*
X570210Y193025D01*
X463600D01*
G01X459000Y190800D02*
X470700D01*
X470925Y190575D01*
X571225D01*
X573300Y192650D01*
X588220D01*
X588221Y192649D01*
X595262D01*
X631025Y228412D01*
Y245375D01*
X630000Y246400D01*
Y256000D01*
X632432Y258432D01*
Y263495D01*
X634269Y265332D01*
X634280D01*
G01X456400Y183700D02*
X474900D01*
X493500Y185675D01*
X595218D01*
X635925Y226382D01*
Y247000D01*
X633262Y251100D01*
Y255562D01*
X636055Y258355D01*
Y263376D01*
X638019Y265340D01*
X638090D01*
G01X461000Y187200D02*
X471000D01*
X471925Y188125D01*
X580475D01*
X582550Y190200D01*
X587205D01*
X587206Y190199D01*
X596277D01*
X633475Y227397D01*
Y246225D01*
X631600Y248100D01*
Y255900D01*
X634207Y258507D01*
Y260300D01*
G01X626682D02*
Y258182D01*
X625200Y256700D01*
Y244400D01*
X621488Y240688D01*
Y235012D01*
X618075Y231599D01*
Y228840D01*
X606315Y217080D01*
X603919D01*
X596335Y209496D01*
Y207100D01*
X589235Y200000D01*
X570255D01*
X568180Y197925D01*
X465175D01*
X463100Y200000D01*
G01X626651Y265489D02*
Y265471D01*
X624905Y263725D01*
Y258205D01*
X623400Y256700D01*
Y245200D01*
X619141Y240941D01*
Y237259D01*
X613325Y231443D01*
Y228871D01*
X604574Y220120D01*
X603494D01*
X593885Y210511D01*
Y208115D01*
X588220Y202450D01*
X569240D01*
X567165Y200375D01*
X465025D01*
X463725Y201675D01*
G01X464425Y195475D02*
X569195D01*
X571270Y197550D01*
X590250D01*
X598785Y206085D01*
Y208481D01*
X604934Y214630D01*
X607330D01*
X620525Y227825D01*
Y230584D01*
X626900Y236959D01*
Y256646D01*
X628657Y258403D01*
Y263543D01*
X630455Y265341D01*
Y265400D01*
G54D16*
G01X74000Y271400D02*
X70100D01*
X62400Y263700D01*
Y258500D01*
X57800Y253900D01*
G01X138600Y146300D02*
X136800Y144500D01*
X130000D01*
X126500Y141000D01*
Y137500D01*
X121900Y132900D01*
X120047D01*
X113947Y139000D01*
X111430D01*
X106100Y144330D01*
Y158700D01*
G01X137100Y188900D02*
X134600D01*
X132000Y186300D01*
Y163000D01*
X136100Y158900D01*
X137300D01*
G01X202761Y186811D02*
Y188391D01*
X205500Y191130D01*
Y193100D01*
X215384Y202984D01*
G01X287400Y254100D02*
X290325Y251175D01*
X323075D01*
X326000Y254100D01*
G54D17*
G01X96200Y60700D02*
Y70139D01*
X116700Y90639D01*
Y116877D01*
X120823Y121000D01*
X130000D01*
G01X119600Y143300D02*
X122700Y140200D01*
Y137500D01*
X120700Y135500D01*
G01X142900Y138595D02*
X136805Y132500D01*
X130820D01*
X127500Y129180D01*
G01X147400Y60400D02*
X150006D01*
X175800Y86194D01*
Y98300D01*
X181526Y104026D01*
Y107265D01*
X182814Y108553D01*
X184253D01*
X202800Y127100D01*
X211096D01*
X216550Y132554D01*
Y138785D01*
X224252Y146487D01*
Y148212D01*
X229175Y153135D01*
Y163759D01*
X232921Y167505D01*
G01X235400Y63400D02*
X234800D01*
X230800Y59400D01*
Y54200D01*
X233300Y51700D01*
X239394D01*
X249994Y41100D01*
X254600D01*
G01X268900Y129386D02*
X266000Y132286D01*
Y143600D01*
X272300Y149900D01*
G01X278300Y173300D02*
Y182128D01*
X286300Y190128D01*
Y191885D01*
G01X349600Y194800D02*
X350959Y193441D01*
Y192094D01*
X351200Y191853D01*
X353904Y189150D01*
X356467D01*
X358750Y186867D01*
Y168550D01*
X356492Y166292D01*
Y161285D01*
X358477Y159300D01*
G01X388000Y72963D02*
X381500Y79463D01*
Y93500D01*
X380020Y94980D01*
Y102520D01*
X384711Y107211D01*
Y109579D01*
X387600Y112468D01*
Y129284D01*
X387530Y129354D01*
Y134480D01*
X389848Y136798D01*
Y137118D01*
G01X435700Y243250D02*
X433325Y240875D01*
X423125D01*
X420000Y244000D01*
G01X511500Y119500D02*
X513700Y121700D01*
X525900D01*
X528100Y119500D01*
G54D18*
G01X477913Y45276D02*
X457913D01*
G54D19*
G01X299800Y82300D02*
X302150Y84650D01*
Y86926D01*
X301000Y88076D01*
Y90858D01*
X299400Y92458D01*
Y95000D01*
X297150Y97250D01*
Y100200D01*
X298714Y101764D01*
Y139982D01*
X298550Y140146D01*
Y146638D01*
X303000Y151088D01*
Y157743D01*
X307231Y161974D01*
Y164059D01*
M02*
